FILE_TYPE = MACRO_DRAWING;
SET COLOR_WIRE YELLOW;
SET COLOR_PROP MONO;
SET COLOR_DOT WHITE;
SET COLOR_ARC YELLOW;
SET COLOR_BODY GREEN;
SET COLOR_NOTE MONO;
SET PROP_DISPLAY VALUE;
SET PAGE_NUMBER P159;
FORCEADD OFFPAGE..3
R 2
(-650 4450);
FORCEPROP 2 LAST CDS_LIB mstr_standard
J 0
(-650 4450);
PAINT ORANGE (-650 4450);
DISPLAY INVISIBLE (-650 4450);
FORCEPROP 1 LAST COMMENT_BODY TRUE
J 2
(-600 4350);
DISPLAY 1.170213 (-600 4350);
PAINT GREEN (-600 4350);
DISPLAY INVISIBLE (-600 4350);
FORCEPROP 2 LAST PATH I111
J 0
(-925 4500);
DISPLAY 1.021277 (-925 4500);
PAINT ORANGE (-925 4500);
DISPLAY INVISIBLE (-925 4500);
FORCEPROP 1 LAST OFFPAGE TRUE
J 2
(-975 4325);
PAINT GREEN (-975 4325);
DISPLAY INVISIBLE (-975 4325);
FORCEPROP 2 LAST $XR0 144 
J 0
(-930 4450);
DISPLAY 0.638298 (-930 4450);
PAINT MONO (-930 4450);
FORCEADD OFFPAGE..4
R 2
(-650 4275);
FORCEPROP 1 LAST COMMENT_BODY TRUE
J 2
(-625 4175);
DISPLAY 0.872340 (-625 4175);
PAINT GREEN (-625 4175);
DISPLAY INVISIBLE (-625 4175);
FORCEPROP 2 LAST CDS_LIB mstr_standard
J 0
(-650 4275);
PAINT ORANGE (-650 4275);
DISPLAY INVISIBLE (-650 4275);
FORCEPROP 2 LAST PATH I112
J 0
(-900 4325);
DISPLAY 1.021277 (-900 4325);
PAINT ORANGE (-900 4325);
DISPLAY INVISIBLE (-900 4325);
FORCEPROP 1 LAST OFFPAGE TRUE
J 2
(-975 4150);
DISPLAY 0.872340 (-975 4150);
PAINT GREEN (-975 4150);
DISPLAY INVISIBLE (-975 4150);
FORCEPROP 2 LAST $XR0 144 
J 0
(-902 4275);
DISPLAY 0.638298 (-902 4275);
PAINT MONO (-902 4275);
FORCEADD OFFPAGE..4
R 2
(-625 3375);
FORCEPROP 2 LAST CDS_LIB mstr_standard
J 0
(-625 3375);
PAINT ORANGE (-625 3375);
DISPLAY INVISIBLE (-625 3375);
FORCEPROP 1 LAST COMMENT_BODY TRUE
J 2
(-600 3275);
DISPLAY 0.872340 (-600 3275);
PAINT GREEN (-600 3275);
DISPLAY INVISIBLE (-600 3275);
FORCEPROP 2 LAST PATH I113
J 0
(-875 3425);
DISPLAY 1.021277 (-875 3425);
PAINT ORANGE (-875 3425);
DISPLAY INVISIBLE (-875 3425);
FORCEPROP 1 LAST OFFPAGE TRUE
J 2
(-950 3250);
DISPLAY 0.872340 (-950 3250);
PAINT GREEN (-950 3250);
DISPLAY INVISIBLE (-950 3250);
FORCEPROP 2 LAST $XR0 144 
J 0
(-907 3375);
DISPLAY 0.638298 (-907 3375);
PAINT MONO (-907 3375);
FORCEADD OFFPAGE..3
R 2
(-600 3550);
FORCEPROP 2 LAST PATH I114
J 0
(-875 3600);
DISPLAY 1.021277 (-875 3600);
PAINT ORANGE (-875 3600);
DISPLAY INVISIBLE (-875 3600);
FORCEPROP 2 LAST CDS_LIB mstr_standard
J 0
(-600 3550);
PAINT ORANGE (-600 3550);
DISPLAY INVISIBLE (-600 3550);
FORCEPROP 1 LAST COMMENT_BODY TRUE
J 2
(-550 3450);
DISPLAY 1.170213 (-550 3450);
PAINT GREEN (-550 3450);
DISPLAY INVISIBLE (-550 3450);
FORCEPROP 1 LAST OFFPAGE TRUE
J 2
(-925 3425);
PAINT GREEN (-925 3425);
DISPLAY INVISIBLE (-925 3425);
FORCEPROP 2 LAST $XR0 144 
J 0
(-880 3550);
DISPLAY 0.638298 (-880 3550);
PAINT MONO (-880 3550);
FORCEADD OFFPAGE..3
R 2
(-575 1775);
FORCEPROP 2 LAST CDS_LIB mstr_standard
J 0
(-575 1775);
PAINT ORANGE (-575 1775);
DISPLAY INVISIBLE (-575 1775);
FORCEPROP 1 LAST COMMENT_BODY TRUE
J 2
(-525 1675);
DISPLAY 1.170213 (-525 1675);
PAINT GREEN (-525 1675);
DISPLAY INVISIBLE (-525 1675);
FORCEPROP 2 LAST PATH I117
J 0
(-850 1825);
DISPLAY 1.021277 (-850 1825);
PAINT ORANGE (-850 1825);
DISPLAY INVISIBLE (-850 1825);
FORCEPROP 1 LAST OFFPAGE TRUE
J 2
(-900 1650);
PAINT GREEN (-900 1650);
DISPLAY INVISIBLE (-900 1650);
FORCEPROP 2 LAST $XR0 144 
J 0
(-855 1775);
DISPLAY 0.638298 (-855 1775);
PAINT MONO (-855 1775);
FORCEADD OFFPAGE..4
R 2
(-600 1600);
FORCEPROP 2 LAST CDS_LIB mstr_standard
J 0
(-600 1600);
PAINT ORANGE (-600 1600);
DISPLAY INVISIBLE (-600 1600);
FORCEPROP 2 LAST PATH I118
J 0
(-850 1650);
DISPLAY 1.021277 (-850 1650);
PAINT ORANGE (-850 1650);
DISPLAY INVISIBLE (-850 1650);
FORCEPROP 1 LAST COMMENT_BODY TRUE
J 2
(-575 1500);
DISPLAY 0.872340 (-575 1500);
PAINT GREEN (-575 1500);
DISPLAY INVISIBLE (-575 1500);
FORCEPROP 1 LAST OFFPAGE TRUE
J 2
(-925 1475);
DISPLAY 0.872340 (-925 1475);
PAINT GREEN (-925 1475);
DISPLAY INVISIBLE (-925 1475);
FORCEPROP 2 LAST $XR0 144 
J 0
(-882 1600);
DISPLAY 0.638298 (-882 1600);
PAINT MONO (-882 1600);
FORCEADD OFFPAGE..3
(-2000 4375);
FORCEPROP 2 LAST PATH I161
J 0
(-1525 4425);
DISPLAY 1.021277 (-1525 4425);
PAINT ORANGE (-1525 4425);
DISPLAY INVISIBLE (-1525 4425);
FORCEPROP 1 LAST OFFPAGE TRUE
J 0
(-1675 4250);
DISPLAY 0.872340 (-1675 4250);
PAINT GREEN (-1675 4250);
DISPLAY INVISIBLE (-1675 4250);
FORCEPROP 2 LAST CDS_LIB mstr_standard
J 0
(-2000 4375);
PAINT ORANGE (-2000 4375);
DISPLAY INVISIBLE (-2000 4375);
FORCEPROP 1 LAST COMMENT_BODY TRUE
J 0
(-2050 4275);
DISPLAY 0.872340 (-2050 4275);
PAINT GREEN (-2050 4275);
DISPLAY INVISIBLE (-2050 4275);
FORCEPROP 2 LAST $XR2 159 
J 0
(-1546 4375);
DISPLAY 0.638298 (-1546 4375);
PAINT MONO (-1546 4375);
FORCEPROP 2 LAST $XR1 156 
J 0
(-1666 4375);
DISPLAY 0.638298 (-1666 4375);
PAINT MONO (-1666 4375);
FORCEPROP 2 LAST $XR0 138 
J 0
(-1786 4375);
DISPLAY 0.638298 (-1786 4375);
PAINT MONO (-1786 4375);
FORCEADD OFFPAGE..2
(-2000 4200);
FORCEPROP 2 LAST PATH I162
J 0
(-1825 4275);
DISPLAY 1.021277 (-1825 4275);
PAINT ORANGE (-1825 4275);
DISPLAY INVISIBLE (-1825 4275);
FORCEPROP 1 LAST COMMENT_BODY TRUE
J 0
(-2045 4105);
DISPLAY 0.872340 (-2045 4105);
PAINT GREEN (-2045 4105);
DISPLAY INVISIBLE (-2045 4105);
FORCEPROP 2 LAST CDS_LIB mstr_standard
J 0
(-2000 4200);
PAINT ORANGE (-2000 4200);
DISPLAY INVISIBLE (-2000 4200);
FORCEPROP 1 LAST OFFPAGE TRUE
J 0
(-1675 4075);
DISPLAY 0.872340 (-1675 4075);
PAINT GREEN (-1675 4075);
DISPLAY INVISIBLE (-1675 4075);
FORCEPROP 2 LAST $XR2 159 
J 0
(-1571 4200);
DISPLAY 0.638298 (-1571 4200);
PAINT MONO (-1571 4200);
FORCEPROP 2 LAST $XR1 156 
J 0
(-1691 4200);
DISPLAY 0.638298 (-1691 4200);
PAINT MONO (-1691 4200);
FORCEPROP 2 LAST $XR0 138 
J 0
(-1811 4200);
DISPLAY 0.638298 (-1811 4200);
PAINT MONO (-1811 4200);
FORCEADD OFFPAGE..3
(-2000 3775);
FORCEPROP 2 LAST PATH I168
J 0
(-1525 3825);
DISPLAY 1.021277 (-1525 3825);
PAINT ORANGE (-1525 3825);
DISPLAY INVISIBLE (-1525 3825);
FORCEPROP 1 LAST OFFPAGE TRUE
J 0
(-1675 3650);
DISPLAY 0.872340 (-1675 3650);
PAINT GREEN (-1675 3650);
DISPLAY INVISIBLE (-1675 3650);
FORCEPROP 2 LAST CDS_LIB mstr_standard
J 0
(-2000 3775);
PAINT ORANGE (-2000 3775);
DISPLAY INVISIBLE (-2000 3775);
FORCEPROP 1 LAST COMMENT_BODY TRUE
J 0
(-2050 3675);
DISPLAY 0.872340 (-2050 3675);
PAINT GREEN (-2050 3675);
DISPLAY INVISIBLE (-2050 3675);
FORCEPROP 2 LAST $XR5 247 
J 0
(-1306 3775);
DISPLAY 0.638298 (-1306 3775);
PAINT MONO (-1306 3775);
FORCEPROP 2 LAST $XR4 156 
J 0
(-1306 3775);
DISPLAY 0.638298 (-1306 3775);
PAINT MONO (-1306 3775);
FORCEPROP 2 LAST $XR3 138 
J 0
(-1426 3775);
DISPLAY 0.638298 (-1426 3775);
PAINT MONO (-1426 3775);
FORCEPROP 2 LAST $XR2 111 
J 0
(-1546 3775);
DISPLAY 0.638298 (-1546 3775);
PAINT MONO (-1546 3775);
FORCEPROP 2 LAST $XR1 102 
J 0
(-1666 3775);
DISPLAY 0.638298 (-1666 3775);
PAINT MONO (-1666 3775);
FORCEPROP 2 LAST $XR0 101 
J 0
(-1786 3775);
DISPLAY 0.638298 (-1786 3775);
PAINT MONO (-1786 3775);
FORCEADD OFFPAGE..2
(-2000 3600);
FORCEPROP 2 LAST PATH I169
J 0
(-1825 3675);
DISPLAY 1.021277 (-1825 3675);
PAINT ORANGE (-1825 3675);
DISPLAY INVISIBLE (-1825 3675);
FORCEPROP 2 LAST CDS_LIB mstr_standard
J 0
(-2000 3600);
PAINT ORANGE (-2000 3600);
DISPLAY INVISIBLE (-2000 3600);
FORCEPROP 1 LAST COMMENT_BODY TRUE
J 0
(-2045 3505);
DISPLAY 0.872340 (-2045 3505);
PAINT GREEN (-2045 3505);
DISPLAY INVISIBLE (-2045 3505);
FORCEPROP 1 LAST OFFPAGE TRUE
J 0
(-1675 3475);
DISPLAY 0.872340 (-1675 3475);
PAINT GREEN (-1675 3475);
DISPLAY INVISIBLE (-1675 3475);
FORCEPROP 2 LAST $XR5 247 
J 0
(-1331 3600);
DISPLAY 0.638298 (-1331 3600);
PAINT MONO (-1331 3600);
FORCEPROP 2 LAST $XR4 156 
J 0
(-1331 3600);
DISPLAY 0.638298 (-1331 3600);
PAINT MONO (-1331 3600);
FORCEPROP 2 LAST $XR3 111 
J 0
(-1451 3600);
DISPLAY 0.638298 (-1451 3600);
PAINT MONO (-1451 3600);
FORCEPROP 2 LAST $XR2 102 
J 0
(-1571 3600);
DISPLAY 0.638298 (-1571 3600);
PAINT MONO (-1571 3600);
FORCEPROP 2 LAST $XR1 101 
J 0
(-1691 3600);
DISPLAY 0.638298 (-1691 3600);
PAINT MONO (-1691 3600);
FORCEPROP 2 LAST $XR0 138 
J 0
(-1811 3600);
DISPLAY 0.638298 (-1811 3600);
PAINT MONO (-1811 3600);
FORCEADD OFFPAGE..3
(-1950 2525);
FORCEPROP 2 LAST PATH I170
J 0
(-1475 2575);
DISPLAY 1.021277 (-1475 2575);
PAINT ORANGE (-1475 2575);
DISPLAY INVISIBLE (-1475 2575);
FORCEPROP 2 LAST CDS_LIB mstr_standard
J 0
(-1950 2525);
PAINT ORANGE (-1950 2525);
DISPLAY INVISIBLE (-1950 2525);
FORCEPROP 1 LAST OFFPAGE TRUE
J 0
(-1625 2400);
DISPLAY 0.872340 (-1625 2400);
PAINT GREEN (-1625 2400);
DISPLAY INVISIBLE (-1625 2400);
FORCEPROP 1 LAST COMMENT_BODY TRUE
J 0
(-2000 2425);
DISPLAY 0.872340 (-2000 2425);
PAINT GREEN (-2000 2425);
DISPLAY INVISIBLE (-2000 2425);
FORCEPROP 2 LAST $XR1 186 
J 0
(-1616 2525);
DISPLAY 0.638298 (-1616 2525);
PAINT MONO (-1616 2525);
FORCEPROP 2 LAST $XR0 159 
J 0
(-1736 2525);
DISPLAY 0.638298 (-1736 2525);
PAINT MONO (-1736 2525);
FORCEADD OFFPAGE..2
(-1950 2350);
FORCEPROP 2 LAST PATH I171
J 0
(-1500 2400);
DISPLAY 1.021277 (-1500 2400);
PAINT ORANGE (-1500 2400);
DISPLAY INVISIBLE (-1500 2400);
FORCEPROP 1 LAST OFFPAGE TRUE
J 0
(-1625 2225);
DISPLAY 0.872340 (-1625 2225);
PAINT GREEN (-1625 2225);
DISPLAY INVISIBLE (-1625 2225);
FORCEPROP 2 LAST CDS_LIB mstr_standard
J 0
(-1950 2350);
PAINT ORANGE (-1950 2350);
DISPLAY INVISIBLE (-1950 2350);
FORCEPROP 1 LAST COMMENT_BODY TRUE
J 0
(-1995 2255);
DISPLAY 0.872340 (-1995 2255);
PAINT GREEN (-1995 2255);
DISPLAY INVISIBLE (-1995 2255);
FORCEPROP 2 LAST $XR1 186 
J 0
(-1641 2350);
DISPLAY 0.638298 (-1641 2350);
PAINT MONO (-1641 2350);
FORCEPROP 2 LAST $XR0 159 
J 0
(-1761 2350);
DISPLAY 0.638298 (-1761 2350);
PAINT MONO (-1761 2350);
FORCEADD OFFPAGE..3
R 2
(-4450 4375);
FORCEPROP 2 LAST CDS_LIB mstr_standard
J 0
(-4450 4375);
PAINT ORANGE (-4450 4375);
DISPLAY INVISIBLE (-4450 4375);
FORCEPROP 1 LAST COMMENT_BODY TRUE
J 2
(-4400 4275);
DISPLAY 1.170213 (-4400 4275);
PAINT GREEN (-4400 4275);
DISPLAY INVISIBLE (-4400 4275);
FORCEPROP 2 LAST PATH I185
J 0
(-4725 4425);
DISPLAY 1.021277 (-4725 4425);
PAINT ORANGE (-4725 4425);
DISPLAY INVISIBLE (-4725 4425);
FORCEPROP 1 LAST OFFPAGE TRUE
J 2
(-4775 4250);
PAINT GREEN (-4775 4250);
DISPLAY INVISIBLE (-4775 4250);
FORCEPROP 2 LAST $XR0 144 
J 0
(-4730 4375);
DISPLAY 0.638298 (-4730 4375);
PAINT MONO (-4730 4375);
FORCEADD OFFPAGE..4
R 2
(-4450 4200);
FORCEPROP 2 LAST PATH I186
J 0
(-4400 4275);
DISPLAY 1.021277 (-4400 4275);
PAINT ORANGE (-4400 4275);
DISPLAY INVISIBLE (-4400 4275);
FORCEPROP 1 LAST COMMENT_BODY TRUE
J 2
(-4425 4100);
DISPLAY 0.872340 (-4425 4100);
PAINT GREEN (-4425 4100);
DISPLAY INVISIBLE (-4425 4100);
FORCEPROP 2 LAST CDS_LIB mstr_standard
J 0
(-4450 4200);
PAINT ORANGE (-4450 4200);
DISPLAY INVISIBLE (-4450 4200);
FORCEPROP 1 LAST OFFPAGE TRUE
J 2
(-4775 4075);
DISPLAY 0.872340 (-4775 4075);
PAINT GREEN (-4775 4075);
DISPLAY INVISIBLE (-4775 4075);
FORCEPROP 2 LAST $XR0 144 
J 0
(-4702 4200);
DISPLAY 0.638298 (-4702 4200);
PAINT MONO (-4702 4200);
FORCEADD OFFPAGE..3
R 2
(-4450 3775);
FORCEPROP 2 LAST CDS_LIB mstr_standard
J 0
(-4450 3775);
PAINT ORANGE (-4450 3775);
DISPLAY INVISIBLE (-4450 3775);
FORCEPROP 1 LAST COMMENT_BODY TRUE
J 2
(-4400 3675);
DISPLAY 1.170213 (-4400 3675);
PAINT GREEN (-4400 3675);
DISPLAY INVISIBLE (-4400 3675);
FORCEPROP 2 LAST PATH I187
J 0
(-4725 3825);
DISPLAY 1.021277 (-4725 3825);
PAINT ORANGE (-4725 3825);
DISPLAY INVISIBLE (-4725 3825);
FORCEPROP 1 LAST OFFPAGE TRUE
J 2
(-4775 3650);
PAINT GREEN (-4775 3650);
DISPLAY INVISIBLE (-4775 3650);
FORCEPROP 2 LAST $XR0 144 
J 0
(-4730 3775);
DISPLAY 0.638298 (-4730 3775);
PAINT MONO (-4730 3775);
FORCEADD OFFPAGE..4
R 2
(-4450 3600);
FORCEPROP 2 LAST PATH I188
J 0
(-4400 3675);
DISPLAY 1.021277 (-4400 3675);
PAINT ORANGE (-4400 3675);
DISPLAY INVISIBLE (-4400 3675);
FORCEPROP 2 LAST CDS_LIB mstr_standard
J 0
(-4450 3600);
PAINT ORANGE (-4450 3600);
DISPLAY INVISIBLE (-4450 3600);
FORCEPROP 1 LAST COMMENT_BODY TRUE
J 2
(-4425 3500);
DISPLAY 0.872340 (-4425 3500);
PAINT GREEN (-4425 3500);
DISPLAY INVISIBLE (-4425 3500);
FORCEPROP 1 LAST OFFPAGE TRUE
J 2
(-4775 3475);
DISPLAY 0.872340 (-4775 3475);
PAINT GREEN (-4775 3475);
DISPLAY INVISIBLE (-4775 3475);
FORCEPROP 2 LAST $XR0 144 
J 0
(-4702 3600);
DISPLAY 0.638298 (-4702 3600);
PAINT MONO (-4702 3600);
FORCEADD OFFPAGE..3
R 2
(-4400 2525);
FORCEPROP 2 LAST CDS_LIB mstr_standard
J 0
(-4400 2525);
PAINT ORANGE (-4400 2525);
DISPLAY INVISIBLE (-4400 2525);
FORCEPROP 1 LAST COMMENT_BODY TRUE
J 2
(-4350 2425);
DISPLAY 1.170213 (-4350 2425);
PAINT GREEN (-4350 2425);
DISPLAY INVISIBLE (-4350 2425);
FORCEPROP 2 LAST PATH I189
J 0
(-4675 2575);
DISPLAY 1.021277 (-4675 2575);
PAINT ORANGE (-4675 2575);
DISPLAY INVISIBLE (-4675 2575);
FORCEPROP 1 LAST OFFPAGE TRUE
J 2
(-4725 2400);
PAINT GREEN (-4725 2400);
DISPLAY INVISIBLE (-4725 2400);
FORCEPROP 2 LAST $XR0 144 
J 0
(-4680 2525);
DISPLAY 0.638298 (-4680 2525);
PAINT MONO (-4680 2525);
FORCEADD OFFPAGE..4
R 2
(-4400 2350);
FORCEPROP 2 LAST CDS_LIB mstr_standard
J 0
(-4400 2350);
PAINT ORANGE (-4400 2350);
DISPLAY INVISIBLE (-4400 2350);
FORCEPROP 1 LAST COMMENT_BODY TRUE
J 2
(-4375 2250);
DISPLAY 0.872340 (-4375 2250);
PAINT GREEN (-4375 2250);
DISPLAY INVISIBLE (-4375 2250);
FORCEPROP 2 LAST PATH I190
J 0
(-4650 2400);
DISPLAY 1.021277 (-4650 2400);
PAINT ORANGE (-4650 2400);
DISPLAY INVISIBLE (-4650 2400);
FORCEPROP 1 LAST OFFPAGE TRUE
J 2
(-4725 2225);
DISPLAY 0.872340 (-4725 2225);
PAINT GREEN (-4725 2225);
DISPLAY INVISIBLE (-4725 2225);
FORCEPROP 2 LAST $XR0 144 
J 0
(-4682 2350);
DISPLAY 0.638298 (-4682 2350);
PAINT MONO (-4682 2350);
FORCEADD OFFPAGE..6
(-4625 1450);
FORCEPROP 2 LAST PATH I195
J 0
(-4575 1525);
DISPLAY 1.021277 (-4575 1525);
PAINT ORANGE (-4575 1525);
DISPLAY INVISIBLE (-4575 1525);
FORCEPROP 1 LAST OFFPAGE TRUE
J 0
(-4300 1325);
DISPLAY 0.872340 (-4300 1325);
PAINT GREEN (-4300 1325);
DISPLAY INVISIBLE (-4300 1325);
FORCEPROP 1 LAST COMMENT_BODY TRUE
J 0
(-4525 1375);
DISPLAY 0.872340 (-4525 1375);
PAINT GREEN (-4525 1375);
DISPLAY INVISIBLE (-4525 1375);
FORCEPROP 2 LAST CDS_LIB mstr_standard
J 0
(-4625 1450);
PAINT MONO (-4625 1450);
DISPLAY INVISIBLE (-4625 1450);
FORCEPROP 2 LAST $XR2 159 
J 0
(-5145 1450);
DISPLAY 0.638298 (-5145 1450);
PAINT MONO (-5145 1450);
FORCEPROP 2 LAST $XR1 156 
J 0
(-5025 1450);
DISPLAY 0.638298 (-5025 1450);
PAINT MONO (-5025 1450);
FORCEPROP 2 LAST $XR0 138 
J 0
(-4905 1450);
DISPLAY 0.638298 (-4905 1450);
PAINT MONO (-4905 1450);
FORCEADD OFFPAGE..1
(-4625 1325);
FORCEPROP 1 LAST OFFPAGE TRUE
J 0
(-4300 1200);
DISPLAY 0.872340 (-4300 1200);
PAINT GREEN (-4300 1200);
DISPLAY INVISIBLE (-4300 1200);
FORCEPROP 2 LAST PATH I196
J 0
(-4575 1400);
DISPLAY 1.021277 (-4575 1400);
PAINT ORANGE (-4575 1400);
DISPLAY INVISIBLE (-4575 1400);
FORCEPROP 1 LAST COMMENT_BODY TRUE
J 0
(-4500 1225);
DISPLAY 0.872340 (-4500 1225);
PAINT GREEN (-4500 1225);
DISPLAY INVISIBLE (-4500 1225);
FORCEPROP 2 LAST CDS_LIB mstr_standard
J 0
(-4625 1325);
PAINT MONO (-4625 1325);
DISPLAY INVISIBLE (-4625 1325);
FORCEPROP 2 LAST $XR2 156 
J 0
(-5147 1325);
DISPLAY 0.638298 (-5147 1325);
PAINT MONO (-5147 1325);
FORCEPROP 2 LAST $XR1 159 
J 0
(-5027 1325);
DISPLAY 0.638298 (-5027 1325);
PAINT MONO (-5027 1325);
FORCEPROP 2 LAST $XR0 138 
J 0
(-4907 1325);
DISPLAY 0.638298 (-4907 1325);
PAINT MONO (-4907 1325);
FORCEADD OFFPAGE..6
(-4625 1575);
FORCEPROP 2 LAST PATH I197
J 0
(-4575 1650);
DISPLAY 1.021277 (-4575 1650);
PAINT ORANGE (-4575 1650);
DISPLAY INVISIBLE (-4575 1650);
FORCEPROP 1 LAST COMMENT_BODY TRUE
J 0
(-4525 1500);
DISPLAY 0.872340 (-4525 1500);
PAINT GREEN (-4525 1500);
DISPLAY INVISIBLE (-4525 1500);
FORCEPROP 1 LAST OFFPAGE TRUE
J 0
(-4300 1450);
DISPLAY 0.872340 (-4300 1450);
PAINT GREEN (-4300 1450);
DISPLAY INVISIBLE (-4300 1450);
FORCEPROP 2 LAST CDS_LIB mstr_standard
J 0
(-4625 1575);
PAINT MONO (-4625 1575);
DISPLAY INVISIBLE (-4625 1575);
FORCEPROP 2 LAST $XR1 186 
J 0
(-5025 1575);
DISPLAY 0.638298 (-5025 1575);
PAINT MONO (-5025 1575);
FORCEPROP 2 LAST $XR0 159 
J 0
(-4905 1575);
DISPLAY 0.638298 (-4905 1575);
PAINT MONO (-4905 1575);
FORCEADD OFFPAGE..1
(-4625 1200);
FORCEPROP 1 LAST OFFPAGE TRUE
J 0
(-4300 1075);
DISPLAY 0.872340 (-4300 1075);
PAINT GREEN (-4300 1075);
DISPLAY INVISIBLE (-4300 1075);
FORCEPROP 2 LAST PATH I198
J 0
(-4575 1275);
DISPLAY 1.021277 (-4575 1275);
PAINT ORANGE (-4575 1275);
DISPLAY INVISIBLE (-4575 1275);
FORCEPROP 1 LAST COMMENT_BODY TRUE
J 0
(-4500 1100);
DISPLAY 0.872340 (-4500 1100);
PAINT GREEN (-4500 1100);
DISPLAY INVISIBLE (-4500 1100);
FORCEPROP 2 LAST CDS_LIB mstr_standard
J 0
(-4625 1200);
PAINT MONO (-4625 1200);
DISPLAY INVISIBLE (-4625 1200);
FORCEPROP 2 LAST $XR1 186 
J 0
(-5027 1200);
DISPLAY 0.638298 (-5027 1200);
PAINT MONO (-5027 1200);
FORCEPROP 2 LAST $XR0 159 
J 0
(-4907 1200);
DISPLAY 0.638298 (-4907 1200);
PAINT MONO (-4907 1200);
FORCEADD OFFPAGE..3
(-2500 1450);
FORCEPROP 2 LAST PATH I199
J 0
(-2450 1525);
DISPLAY 1.021277 (-2450 1525);
PAINT ORANGE (-2450 1525);
DISPLAY INVISIBLE (-2450 1525);
FORCEPROP 1 LAST OFFPAGE TRUE
J 0
(-2175 1325);
DISPLAY 0.872340 (-2175 1325);
PAINT GREEN (-2175 1325);
DISPLAY INVISIBLE (-2175 1325);
FORCEPROP 2 LAST CDS_LIB mstr_standard
J 0
(-2500 1450);
PAINT MONO (-2500 1450);
DISPLAY INVISIBLE (-2500 1450);
FORCEPROP 1 LAST COMMENT_BODY TRUE
J 0
(-2550 1350);
DISPLAY 0.872340 (-2550 1350);
PAINT GREEN (-2550 1350);
DISPLAY INVISIBLE (-2550 1350);
FORCEPROP 2 LAST $XR0 139 
J 0
(-2226 1450);
DISPLAY 0.638298 (-2226 1450);
PAINT MONO (-2226 1450);
FORCEADD OFFPAGE..2
(-2500 1325);
FORCEPROP 1 LAST OFFPAGE TRUE
J 0
(-2175 1200);
DISPLAY 0.872340 (-2175 1200);
PAINT GREEN (-2175 1200);
DISPLAY INVISIBLE (-2175 1200);
FORCEPROP 2 LAST PATH I200
J 0
(-2325 1400);
DISPLAY 1.021277 (-2325 1400);
PAINT ORANGE (-2325 1400);
DISPLAY INVISIBLE (-2325 1400);
FORCEPROP 2 LAST CDS_LIB mstr_standard
J 0
(-2500 1325);
PAINT MONO (-2500 1325);
DISPLAY INVISIBLE (-2500 1325);
FORCEPROP 1 LAST COMMENT_BODY TRUE
J 0
(-2545 1230);
DISPLAY 0.872340 (-2545 1230);
PAINT GREEN (-2545 1230);
DISPLAY INVISIBLE (-2545 1230);
FORCEPROP 2 LAST $XR0 139 
J 0
(-2221 1325);
DISPLAY 0.638298 (-2221 1325);
PAINT MONO (-2221 1325);
FORCEADD P3V3_STBY..1
(-3375 3200);
FORCEPROP 3 LASTPIN (-3375 3150) SIG_NAME P3V3_STBY\g
J 0
(-3365 3160);
DISPLAY 0.659574 (-3365 3160);
PAINT MONO (-3365 3160);
DISPLAY INVISIBLE (-3365 3160);
FORCEPROP 1 LAST PATH I209
J 0
(-3330 3202);
DISPLAY 0.340426 (-3330 3202);
PAINT GREEN (-3330 3202);
DISPLAY INVISIBLE (-3330 3202);
FORCEPROP 1 LAST BODY_TYPE PLUMBING
J 0
(-3420 3157);
DISPLAY 0.340426 (-3420 3157);
PAINT GREEN (-3420 3157);
DISPLAY INVISIBLE (-3420 3157);
FORCEPROP 2 LAST CDS_LIB mstr_symbols
J 0
(-3375 3200);
PAINT MONO (-3375 3200);
DISPLAY INVISIBLE (-3375 3200);
FORCEPROP 1 LAST SIZE 1B
J 0
(-3330 3222);
DISPLAY 0.340426 (-3330 3222);
PAINT GREEN (-3330 3222);
DISPLAY INVISIBLE (-3330 3222);
FORCEPROP 1 LAST VOLTAGE 3.3V
J 0
(-3420 3157);
DISPLAY 0.340426 (-3420 3157);
PAINT SKYBLUE (-3420 3157);
DISPLAY INVISIBLE (-3420 3157);
FORCEPROP 1 LAST HDL_POWER P3V3_STBY
J 0
(-3675 3075);
DISPLAY 0.872340 (-3675 3075);
PAINT ORANGE (-3675 3075);
DISPLAY INVISIBLE (-3675 3075);
FORCEADD RES..2
(-3375 2900);
FORCEPROP 1 LAST PATH I210
J 0
(-3325 3075);
DISPLAY 0.978723 (-3325 3075);
PAINT WHITE (-3325 3075);
DISPLAY INVISIBLE (-3325 3075);
FORCEPROP 2 LAST $SEC 1
J 0
(-3325 3125);
PAINT MONO (-3325 3125);
DISPLAY INVISIBLE (-3325 3125);
FORCEPROP 2 LAST CDS_SEC 1
J 0
(-3325 3125);
PAINT MONO (-3325 3125);
DISPLAY INVISIBLE (-3325 3125);
FORCEPROP 0 LAST BOM_COST SM_CONTROLLER
J 0
(-3325 3225);
DISPLAY 1.021277 (-3325 3225);
PAINT ORANGE (-3325 3225);
DISPLAY INVISIBLE (-3325 3225);
FORCEPROP 0 LAST SKU B
J 0
(-3325 3125);
DISPLAY 1.021277 (-3325 3125);
PAINT ORANGE (-3325 3125);
DISPLAY INVISIBLE (-3325 3125);
FORCEPROP 0 LAST ROOM SMBUS
J 0
(-3325 3125);
DISPLAY 1.021277 (-3325 3125);
PAINT ORANGE (-3325 3125);
DISPLAY INVISIBLE (-3325 3125);
FORCEPROP 2 LAST CDS_LOCATION R8G3
J 0
(-3330 3025);
DISPLAY 0.617021 (-3330 3025);
PAINT AQUA (-3330 3025);
DISPLAY INVISIBLE (-3330 3025);
FORCEPROP 1 LASTPIN (-3375 3000) $PN 1
J 0
(-3370 2962);
DISPLAY 0.787234 (-3370 2962);
PAINT ORANGE (-3370 2962);
DISPLAY INVISIBLE (-3370 2962);
FORCEPROP 2 LAST CDS_LIB mstr_discrete
J 0
(-3375 2900);
PAINT ORANGE (-3375 2900);
DISPLAY INVISIBLE (-3375 2900);
FORCEPROP 1 LASTPIN (-3375 2800) $PN 2
J 0
(-3370 2810);
DISPLAY 0.787234 (-3370 2810);
PAINT ORANGE (-3370 2810);
DISPLAY INVISIBLE (-3370 2810);
FORCEPROP 1 LAST PART_NUMBER G21796-311
J 0
(-3335 2775);
DISPLAY 0.617021 (-3335 2775);
PAINT BLUE (-3335 2775);
FORCEPROP 1 LAST WATTAGE 1/16W
J 0
(-3335 2875);
DISPLAY 0.617021 (-3335 2875);
PAINT SKYBLUE (-3335 2875);
FORCEPROP 1 LAST PACK_TYPE 0402
J 0
(-3335 2725);
DISPLAY 0.617021 (-3335 2725);
PAINT SKYBLUE (-3335 2725);
FORCEPROP 1 LAST TOLERANCE 1.0%
J 0
(-3330 2925);
DISPLAY 0.617021 (-3330 2925);
PAINT SKYBLUE (-3330 2925);
FORCEPROP 1 LAST VALUE 2.26K
J 0
(-3330 2975);
DISPLAY 0.617021 (-3330 2975);
PAINT SKYBLUE (-3330 2975);
FORCEPROP 1 LAST LOCATION R8G3
J 0
(-3330 3025);
DISPLAY 0.617021 (-3330 3025);
PAINT AQUA (-3330 3025);
FORCEPROP 1 LAST MATERIAL EMPTY
J 0
(-3335 2825);
DISPLAY 0.617021 (-3335 2825);
PAINT RED (-3335 2825);
FORCEADD P3V3_STBY..1
(-3725 3200);
FORCEPROP 3 LASTPIN (-3725 3150) SIG_NAME P3V3_STBY\g
J 0
(-3715 3160);
DISPLAY 0.659574 (-3715 3160);
PAINT MONO (-3715 3160);
DISPLAY INVISIBLE (-3715 3160);
FORCEPROP 1 LAST SIZE 1B
J 0
(-3680 3222);
DISPLAY 0.340426 (-3680 3222);
PAINT GREEN (-3680 3222);
DISPLAY INVISIBLE (-3680 3222);
FORCEPROP 1 LAST PATH I211
J 0
(-3680 3202);
DISPLAY 0.340426 (-3680 3202);
PAINT GREEN (-3680 3202);
DISPLAY INVISIBLE (-3680 3202);
FORCEPROP 2 LAST CDS_LIB mstr_symbols
J 0
(-3725 3200);
PAINT MONO (-3725 3200);
DISPLAY INVISIBLE (-3725 3200);
FORCEPROP 1 LAST BODY_TYPE PLUMBING
J 0
(-3770 3157);
DISPLAY 0.340426 (-3770 3157);
PAINT GREEN (-3770 3157);
DISPLAY INVISIBLE (-3770 3157);
FORCEPROP 1 LAST VOLTAGE 3.3V
J 0
(-3770 3157);
DISPLAY 0.340426 (-3770 3157);
PAINT SKYBLUE (-3770 3157);
DISPLAY INVISIBLE (-3770 3157);
FORCEPROP 1 LAST HDL_POWER P3V3_STBY
J 0
(-4025 3075);
DISPLAY 0.872340 (-4025 3075);
PAINT ORANGE (-4025 3075);
DISPLAY INVISIBLE (-4025 3075);
FORCEADD RES..2
(-3725 2900);
FORCEPROP 0 LAST SKU B
J 0
(-3675 3125);
DISPLAY 1.021277 (-3675 3125);
PAINT ORANGE (-3675 3125);
DISPLAY INVISIBLE (-3675 3125);
FORCEPROP 0 LAST BOM_COST SM_CONTROLLER
J 0
(-3675 3225);
DISPLAY 1.021277 (-3675 3225);
PAINT ORANGE (-3675 3225);
DISPLAY INVISIBLE (-3675 3225);
FORCEPROP 2 LAST CDS_SEC 1
J 0
(-3675 3125);
PAINT MONO (-3675 3125);
DISPLAY INVISIBLE (-3675 3125);
FORCEPROP 2 LAST $SEC 1
J 0
(-3675 3125);
PAINT MONO (-3675 3125);
DISPLAY INVISIBLE (-3675 3125);
FORCEPROP 1 LAST PATH I212
J 0
(-3675 3075);
DISPLAY 0.978723 (-3675 3075);
PAINT WHITE (-3675 3075);
DISPLAY INVISIBLE (-3675 3075);
FORCEPROP 0 LAST ROOM SMBUS
J 0
(-3675 3125);
DISPLAY 1.021277 (-3675 3125);
PAINT ORANGE (-3675 3125);
DISPLAY INVISIBLE (-3675 3125);
FORCEPROP 2 LAST CDS_LOCATION R8G6
J 0
(-3680 3025);
DISPLAY 0.617021 (-3680 3025);
PAINT AQUA (-3680 3025);
DISPLAY INVISIBLE (-3680 3025);
FORCEPROP 1 LASTPIN (-3725 3000) $PN 1
J 0
(-3720 2962);
DISPLAY 0.787234 (-3720 2962);
PAINT ORANGE (-3720 2962);
DISPLAY INVISIBLE (-3720 2962);
FORCEPROP 2 LAST CDS_LIB mstr_discrete
J 0
(-3725 2900);
PAINT ORANGE (-3725 2900);
DISPLAY INVISIBLE (-3725 2900);
FORCEPROP 1 LASTPIN (-3725 2800) $PN 2
J 0
(-3720 2810);
DISPLAY 0.787234 (-3720 2810);
PAINT ORANGE (-3720 2810);
DISPLAY INVISIBLE (-3720 2810);
FORCEPROP 1 LAST WATTAGE 1/16W
J 0
(-3685 2875);
DISPLAY 0.617021 (-3685 2875);
PAINT SKYBLUE (-3685 2875);
FORCEPROP 1 LAST PACK_TYPE 0402
J 0
(-3685 2725);
DISPLAY 0.617021 (-3685 2725);
PAINT SKYBLUE (-3685 2725);
FORCEPROP 1 LAST TOLERANCE 1.0%
J 0
(-3680 2925);
DISPLAY 0.617021 (-3680 2925);
PAINT SKYBLUE (-3680 2925);
FORCEPROP 1 LAST VALUE 2.26K
J 0
(-3680 2975);
DISPLAY 0.617021 (-3680 2975);
PAINT SKYBLUE (-3680 2975);
FORCEPROP 1 LAST PART_NUMBER G21796-311
J 0
(-3685 2775);
DISPLAY 0.617021 (-3685 2775);
PAINT BLUE (-3685 2775);
FORCEPROP 1 LAST LOCATION R8G6
J 0
(-3680 3025);
DISPLAY 0.617021 (-3680 3025);
PAINT AQUA (-3680 3025);
FORCEPROP 1 LAST MATERIAL EMPTY
J 0
(-3685 2825);
DISPLAY 0.617021 (-3685 2825);
PAINT RED (-3685 2825);
FORCEADD P3V3_STBY..1
(550 5125);
FORCEPROP 3 LASTPIN (550 5075) SIG_NAME P3V3_STBY\g
J 0
(560 5085);
DISPLAY 0.659574 (560 5085);
PAINT MONO (560 5085);
DISPLAY INVISIBLE (560 5085);
FORCEPROP 2 LAST CDS_LIB mstr_symbols
J 0
(550 5125);
PAINT MONO (550 5125);
DISPLAY INVISIBLE (550 5125);
FORCEPROP 1 LAST SIZE 1B
J 0
(595 5147);
DISPLAY 0.340426 (595 5147);
PAINT GREEN (595 5147);
DISPLAY INVISIBLE (595 5147);
FORCEPROP 1 LAST PATH I213
J 0
(595 5127);
DISPLAY 0.340426 (595 5127);
PAINT GREEN (595 5127);
DISPLAY INVISIBLE (595 5127);
FORCEPROP 1 LAST BODY_TYPE PLUMBING
J 0
(505 5082);
DISPLAY 0.340426 (505 5082);
PAINT GREEN (505 5082);
DISPLAY INVISIBLE (505 5082);
FORCEPROP 1 LAST VOLTAGE 3.3V
J 0
(505 5082);
DISPLAY 0.340426 (505 5082);
PAINT SKYBLUE (505 5082);
DISPLAY INVISIBLE (505 5082);
FORCEPROP 1 LAST HDL_POWER P3V3_STBY
J 0
(250 5000);
DISPLAY 0.872340 (250 5000);
PAINT ORANGE (250 5000);
DISPLAY INVISIBLE (250 5000);
FORCEADD RES..2
(550 4825);
FORCEPROP 0 LAST BOM_COST SM_CONTROLLER
J 0
(600 5150);
DISPLAY 1.021277 (600 5150);
PAINT ORANGE (600 5150);
DISPLAY INVISIBLE (600 5150);
FORCEPROP 2 LAST CDS_SEC 1
J 0
(600 5050);
PAINT MONO (600 5050);
DISPLAY INVISIBLE (600 5050);
FORCEPROP 2 LAST $SEC 1
J 0
(600 5050);
PAINT MONO (600 5050);
DISPLAY INVISIBLE (600 5050);
FORCEPROP 1 LAST PATH I214
J 0
(600 5000);
DISPLAY 0.978723 (600 5000);
PAINT WHITE (600 5000);
DISPLAY INVISIBLE (600 5000);
FORCEPROP 0 LAST SKU B
J 0
(600 5050);
DISPLAY 1.021277 (600 5050);
PAINT ORANGE (600 5050);
DISPLAY INVISIBLE (600 5050);
FORCEPROP 0 LAST ROOM SMBUS
J 0
(600 5050);
DISPLAY 1.021277 (600 5050);
PAINT ORANGE (600 5050);
DISPLAY INVISIBLE (600 5050);
FORCEPROP 1 LASTPIN (550 4925) $PN 1
J 0
(555 4887);
DISPLAY 0.787234 (555 4887);
PAINT ORANGE (555 4887);
DISPLAY INVISIBLE (555 4887);
FORCEPROP 2 LAST CDS_LOCATION R2U5
J 0
(595 4950);
DISPLAY 0.617021 (595 4950);
PAINT AQUA (595 4950);
DISPLAY INVISIBLE (595 4950);
FORCEPROP 2 LAST CDS_LIB mstr_discrete
J 0
(550 4825);
PAINT ORANGE (550 4825);
DISPLAY INVISIBLE (550 4825);
FORCEPROP 1 LASTPIN (550 4725) $PN 2
J 0
(555 4735);
DISPLAY 0.787234 (555 4735);
PAINT ORANGE (555 4735);
DISPLAY INVISIBLE (555 4735);
FORCEPROP 1 LAST PART_NUMBER G21796-311
J 0
(590 4700);
DISPLAY 0.617021 (590 4700);
PAINT BLUE (590 4700);
FORCEPROP 1 LAST VALUE 2.26K
J 0
(595 4900);
DISPLAY 0.617021 (595 4900);
PAINT SKYBLUE (595 4900);
FORCEPROP 1 LAST LOCATION R2U5
J 0
(595 4950);
DISPLAY 0.617021 (595 4950);
PAINT AQUA (595 4950);
FORCEPROP 1 LAST TOLERANCE 1.0%
J 0
(595 4850);
DISPLAY 0.617021 (595 4850);
PAINT SKYBLUE (595 4850);
FORCEPROP 1 LAST PACK_TYPE 0402
J 0
(590 4650);
DISPLAY 0.617021 (590 4650);
PAINT SKYBLUE (590 4650);
FORCEPROP 1 LAST MATERIAL CHIP
J 0
(590 4750);
DISPLAY 0.617021 (590 4750);
PAINT SKYBLUE (590 4750);
FORCEPROP 1 LAST WATTAGE 1/16W
J 0
(590 4800);
DISPLAY 0.617021 (590 4800);
PAINT SKYBLUE (590 4800);
FORCEADD P3V3_STBY..1
(200 5125);
FORCEPROP 3 LASTPIN (200 5075) SIG_NAME P3V3_STBY\g
J 0
(210 5085);
DISPLAY 0.659574 (210 5085);
PAINT MONO (210 5085);
DISPLAY INVISIBLE (210 5085);
FORCEPROP 1 LAST SIZE 1B
J 0
(245 5147);
DISPLAY 0.340426 (245 5147);
PAINT GREEN (245 5147);
DISPLAY INVISIBLE (245 5147);
FORCEPROP 2 LAST CDS_LIB mstr_symbols
J 0
(200 5125);
PAINT MONO (200 5125);
DISPLAY INVISIBLE (200 5125);
FORCEPROP 1 LAST PATH I215
J 0
(245 5127);
DISPLAY 0.340426 (245 5127);
PAINT GREEN (245 5127);
DISPLAY INVISIBLE (245 5127);
FORCEPROP 1 LAST BODY_TYPE PLUMBING
J 0
(155 5082);
DISPLAY 0.340426 (155 5082);
PAINT GREEN (155 5082);
DISPLAY INVISIBLE (155 5082);
FORCEPROP 1 LAST VOLTAGE 3.3V
J 0
(155 5082);
DISPLAY 0.340426 (155 5082);
PAINT SKYBLUE (155 5082);
DISPLAY INVISIBLE (155 5082);
FORCEPROP 1 LAST HDL_POWER P3V3_STBY
J 0
(-100 5000);
DISPLAY 0.872340 (-100 5000);
PAINT ORANGE (-100 5000);
DISPLAY INVISIBLE (-100 5000);
FORCEADD RES..2
(200 4825);
FORCEPROP 0 LAST BOM_COST SM_CONTROLLER
J 0
(250 5150);
DISPLAY 1.021277 (250 5150);
PAINT ORANGE (250 5150);
DISPLAY INVISIBLE (250 5150);
FORCEPROP 2 LAST $SEC 1
J 0
(250 5050);
PAINT MONO (250 5050);
DISPLAY INVISIBLE (250 5050);
FORCEPROP 1 LAST PATH I216
J 0
(250 5000);
DISPLAY 0.978723 (250 5000);
PAINT WHITE (250 5000);
DISPLAY INVISIBLE (250 5000);
FORCEPROP 2 LAST CDS_SEC 1
J 0
(250 5050);
PAINT MONO (250 5050);
DISPLAY INVISIBLE (250 5050);
FORCEPROP 0 LAST ROOM SMBUS
J 0
(250 5050);
DISPLAY 1.021277 (250 5050);
PAINT ORANGE (250 5050);
DISPLAY INVISIBLE (250 5050);
FORCEPROP 0 LAST SKU B
J 0
(250 5050);
DISPLAY 1.021277 (250 5050);
PAINT ORANGE (250 5050);
DISPLAY INVISIBLE (250 5050);
FORCEPROP 2 LAST CDS_LOCATION R2U13
J 0
(245 4950);
DISPLAY 0.617021 (245 4950);
PAINT AQUA (245 4950);
DISPLAY INVISIBLE (245 4950);
FORCEPROP 1 LASTPIN (200 4925) $PN 1
J 0
(205 4887);
DISPLAY 0.787234 (205 4887);
PAINT ORANGE (205 4887);
DISPLAY INVISIBLE (205 4887);
FORCEPROP 2 LAST CDS_LIB mstr_discrete
J 0
(200 4825);
PAINT ORANGE (200 4825);
DISPLAY INVISIBLE (200 4825);
FORCEPROP 1 LASTPIN (200 4725) $PN 2
J 0
(205 4735);
DISPLAY 0.787234 (205 4735);
PAINT ORANGE (205 4735);
DISPLAY INVISIBLE (205 4735);
FORCEPROP 1 LAST PART_NUMBER G21796-311
J 0
(240 4700);
DISPLAY 0.617021 (240 4700);
PAINT BLUE (240 4700);
FORCEPROP 1 LAST PACK_TYPE 0402
J 0
(240 4650);
DISPLAY 0.617021 (240 4650);
PAINT SKYBLUE (240 4650);
FORCEPROP 1 LAST WATTAGE 1/16W
J 0
(240 4800);
DISPLAY 0.617021 (240 4800);
PAINT SKYBLUE (240 4800);
FORCEPROP 1 LAST MATERIAL CHIP
J 0
(240 4750);
DISPLAY 0.617021 (240 4750);
PAINT SKYBLUE (240 4750);
FORCEPROP 1 LAST LOCATION R2U13
J 0
(245 4950);
DISPLAY 0.617021 (245 4950);
PAINT AQUA (245 4950);
FORCEPROP 1 LAST TOLERANCE 1.0%
J 0
(245 4850);
DISPLAY 0.617021 (245 4850);
PAINT SKYBLUE (245 4850);
FORCEPROP 1 LAST VALUE 2.26K
J 0
(245 4900);
DISPLAY 0.617021 (245 4900);
PAINT SKYBLUE (245 4900);
FORCEADD RES..1
(700 3375);
FORCEPROP 2 LAST CDS_SEC 1
J 0
(650 3575);
DISPLAY 1.404255 (650 3575);
PAINT ORANGE (650 3575);
DISPLAY INVISIBLE (650 3575);
FORCEPROP 2 LAST $SEC 1
J 0
(650 3575);
DISPLAY 0.936170 (650 3575);
PAINT MONO (650 3575);
DISPLAY INVISIBLE (650 3575);
FORCEPROP 1 LAST PACK_TYPE 0402
J 0
(950 3225);
PAINT SKYBLUE (950 3225);
DISPLAY INVISIBLE (950 3225);
FORCEPROP 2 LAST BOM_COST SM_CONTROLLER
J 0
(650 3525);
DISPLAY 1.021277 (650 3525);
PAINT ORANGE (650 3525);
DISPLAY INVISIBLE (650 3525);
FORCEPROP 1 LAST PATH I218
J 0
(650 3525);
DISPLAY 0.978723 (650 3525);
PAINT WHITE (650 3525);
DISPLAY INVISIBLE (650 3525);
FORCEPROP 2 LAST ROOM SMBUS
J 0
(650 3475);
DISPLAY 1.021277 (650 3475);
PAINT ORANGE (650 3475);
DISPLAY INVISIBLE (650 3475);
FORCEPROP 1 LAST PART_NUMBER G21796-173
J 0
(650 3450);
PAINT BLUE (650 3450);
DISPLAY INVISIBLE (650 3450);
FORCEPROP 2 LAST CDS_LIB mstr_discrete
J 0
(700 3375);
PAINT ORANGE (700 3375);
DISPLAY INVISIBLE (700 3375);
FORCEPROP 2 LAST CDS_LOCATION R2U1
J 0
(650 3425);
DISPLAY 0.617021 (650 3425);
PAINT AQUA (650 3425);
DISPLAY INVISIBLE (650 3425);
FORCEPROP 1 LAST WATTAGE 1/16W
J 2
(475 3375);
PAINT SKYBLUE (475 3375);
DISPLAY INVISIBLE (475 3375);
FORCEPROP 1 LAST TOLERANCE 1%
J 0
(825 3375);
DISPLAY 0.617021 (825 3375);
PAINT SKYBLUE (825 3375);
FORCEPROP 1 LAST VALUE 20.0
J 2
(1000 3375);
DISPLAY 0.617021 (1000 3375);
PAINT SKYBLUE (1000 3375);
FORCEPROP 1 LASTPIN (800 3375) $PN 2
J 0
(762 3387);
DISPLAY 0.617021 (762 3387);
PAINT MONO (762 3387);
FORCEPROP 1 LAST LOCATION R2U1
J 0
(650 3425);
DISPLAY 0.617021 (650 3425);
PAINT AQUA (650 3425);
FORCEPROP 1 LASTPIN (600 3375) $PN 1
J 0
(612 3387);
DISPLAY 0.617021 (612 3387);
PAINT MONO (612 3387);
FORCEPROP 1 LAST MATERIAL CHIP
J 0
(500 3375);
DISPLAY 0.617021 (500 3375);
PAINT SKYBLUE (500 3375);
FORCEADD RES..1
(700 3550);
FORCEPROP 2 LAST BOM_COST SM_CONTROLLER
J 0
(650 3700);
DISPLAY 1.021277 (650 3700);
PAINT ORANGE (650 3700);
DISPLAY INVISIBLE (650 3700);
FORCEPROP 2 LAST CDS_SEC 1
J 0
(650 3750);
DISPLAY 1.404255 (650 3750);
PAINT ORANGE (650 3750);
DISPLAY INVISIBLE (650 3750);
FORCEPROP 2 LAST $SEC 1
J 0
(650 3750);
DISPLAY 0.936170 (650 3750);
PAINT MONO (650 3750);
DISPLAY INVISIBLE (650 3750);
FORCEPROP 2 LAST CDS_LOCATION R2T49
J 0
(650 3600);
DISPLAY 0.617021 (650 3600);
PAINT AQUA (650 3600);
DISPLAY INVISIBLE (650 3600);
FORCEPROP 1 LAST PATH I219
J 0
(650 3700);
DISPLAY 0.978723 (650 3700);
PAINT WHITE (650 3700);
DISPLAY INVISIBLE (650 3700);
FORCEPROP 2 LAST ROOM SMBUS
J 0
(650 3650);
DISPLAY 1.021277 (650 3650);
PAINT ORANGE (650 3650);
DISPLAY INVISIBLE (650 3650);
FORCEPROP 1 LAST PART_NUMBER G21796-173
J 0
(650 3625);
PAINT BLUE (650 3625);
DISPLAY INVISIBLE (650 3625);
FORCEPROP 2 LAST CDS_LIB mstr_discrete
J 0
(700 3550);
PAINT ORANGE (700 3550);
DISPLAY INVISIBLE (700 3550);
FORCEPROP 1 LAST PACK_TYPE 0402
J 0
(950 3400);
PAINT SKYBLUE (950 3400);
DISPLAY INVISIBLE (950 3400);
FORCEPROP 1 LAST WATTAGE 1/16W
J 2
(475 3550);
PAINT SKYBLUE (475 3550);
DISPLAY INVISIBLE (475 3550);
FORCEPROP 1 LAST LOCATION R2T49
J 0
(650 3600);
DISPLAY 0.617021 (650 3600);
PAINT AQUA (650 3600);
FORCEPROP 1 LASTPIN (800 3550) $PN 2
J 0
(762 3562);
DISPLAY 0.617021 (762 3562);
PAINT MONO (762 3562);
FORCEPROP 1 LASTPIN (600 3550) $PN 1
J 0
(612 3562);
DISPLAY 0.617021 (612 3562);
PAINT MONO (612 3562);
FORCEPROP 1 LAST TOLERANCE 1%
J 0
(825 3550);
DISPLAY 0.617021 (825 3550);
PAINT SKYBLUE (825 3550);
FORCEPROP 1 LAST VALUE 20.0
J 2
(1000 3550);
DISPLAY 0.617021 (1000 3550);
PAINT SKYBLUE (1000 3550);
FORCEPROP 1 LAST MATERIAL CHIP
J 0
(500 3550);
DISPLAY 0.617021 (500 3550);
PAINT SKYBLUE (500 3550);
FORCEADD RES..1
(1025 4275);
FORCEPROP 2 LAST CDS_LIB mstr_discrete
J 0
(1025 4275);
PAINT ORANGE (1025 4275);
DISPLAY INVISIBLE (1025 4275);
FORCEPROP 1 LAST PACK_TYPE 0402
J 0
(1275 4125);
PAINT SKYBLUE (1275 4125);
DISPLAY INVISIBLE (1275 4125);
FORCEPROP 1 LAST PATH I220
J 0
(975 4425);
DISPLAY 0.978723 (975 4425);
PAINT WHITE (975 4425);
DISPLAY INVISIBLE (975 4425);
FORCEPROP 2 LAST $SEC 1
J 0
(975 4475);
DISPLAY 0.936170 (975 4475);
PAINT MONO (975 4475);
DISPLAY INVISIBLE (975 4475);
FORCEPROP 2 LAST CDS_SEC 1
J 0
(975 4475);
DISPLAY 1.404255 (975 4475);
PAINT ORANGE (975 4475);
DISPLAY INVISIBLE (975 4475);
FORCEPROP 2 LAST BOM_COST SM_CONTROLLER
J 0
(975 4425);
DISPLAY 1.021277 (975 4425);
PAINT ORANGE (975 4425);
DISPLAY INVISIBLE (975 4425);
FORCEPROP 2 LAST ROOM SMBUS
J 0
(975 4375);
DISPLAY 1.021277 (975 4375);
PAINT ORANGE (975 4375);
DISPLAY INVISIBLE (975 4375);
FORCEPROP 1 LAST PART_NUMBER G21796-173
J 0
(975 4350);
PAINT BLUE (975 4350);
DISPLAY INVISIBLE (975 4350);
FORCEPROP 2 LAST CDS_LOCATION R2U7
J 0
(975 4325);
DISPLAY 0.617021 (975 4325);
PAINT AQUA (975 4325);
DISPLAY INVISIBLE (975 4325);
FORCEPROP 1 LAST WATTAGE 1/16W
J 2
(800 4275);
PAINT SKYBLUE (800 4275);
DISPLAY INVISIBLE (800 4275);
FORCEPROP 1 LAST VALUE 20.0
J 2
(1325 4275);
DISPLAY 0.617021 (1325 4275);
PAINT SKYBLUE (1325 4275);
FORCEPROP 1 LASTPIN (1125 4275) $PN 2
J 0
(1087 4287);
DISPLAY 0.617021 (1087 4287);
PAINT MONO (1087 4287);
FORCEPROP 1 LAST TOLERANCE 1%
J 0
(1150 4275);
DISPLAY 0.617021 (1150 4275);
PAINT SKYBLUE (1150 4275);
FORCEPROP 1 LAST LOCATION R2U7
J 0
(975 4325);
DISPLAY 0.617021 (975 4325);
PAINT AQUA (975 4325);
FORCEPROP 1 LASTPIN (925 4275) $PN 1
J 0
(937 4287);
DISPLAY 0.617021 (937 4287);
PAINT MONO (937 4287);
FORCEPROP 1 LAST MATERIAL CHIP
J 0
(825 4275);
DISPLAY 0.617021 (825 4275);
PAINT SKYBLUE (825 4275);
FORCEADD RES..1
(1025 4450);
FORCEPROP 2 LAST CDS_LIB mstr_discrete
J 0
(1025 4450);
PAINT ORANGE (1025 4450);
DISPLAY INVISIBLE (1025 4450);
FORCEPROP 1 LAST PACK_TYPE 0402
J 0
(1275 4300);
PAINT SKYBLUE (1275 4300);
DISPLAY INVISIBLE (1275 4300);
FORCEPROP 2 LAST CDS_SEC 1
J 0
(975 4650);
DISPLAY 1.404255 (975 4650);
PAINT ORANGE (975 4650);
DISPLAY INVISIBLE (975 4650);
FORCEPROP 2 LAST $SEC 1
J 0
(975 4650);
DISPLAY 0.936170 (975 4650);
PAINT MONO (975 4650);
DISPLAY INVISIBLE (975 4650);
FORCEPROP 2 LAST BOM_COST SM_CONTROLLER
J 0
(975 4600);
DISPLAY 1.021277 (975 4600);
PAINT ORANGE (975 4600);
DISPLAY INVISIBLE (975 4600);
FORCEPROP 1 LAST PATH I221
J 0
(975 4600);
DISPLAY 0.978723 (975 4600);
PAINT WHITE (975 4600);
DISPLAY INVISIBLE (975 4600);
FORCEPROP 2 LAST CDS_LOCATION R2U10
J 0
(975 4500);
DISPLAY 0.617021 (975 4500);
PAINT AQUA (975 4500);
DISPLAY INVISIBLE (975 4500);
FORCEPROP 2 LAST ROOM SMBUS
J 0
(975 4550);
DISPLAY 1.021277 (975 4550);
PAINT ORANGE (975 4550);
DISPLAY INVISIBLE (975 4550);
FORCEPROP 1 LAST PART_NUMBER G21796-173
J 0
(975 4525);
PAINT BLUE (975 4525);
DISPLAY INVISIBLE (975 4525);
FORCEPROP 1 LAST WATTAGE 1/16W
J 2
(800 4450);
PAINT SKYBLUE (800 4450);
DISPLAY INVISIBLE (800 4450);
FORCEPROP 1 LAST VALUE 20.0
J 2
(1325 4450);
DISPLAY 0.617021 (1325 4450);
PAINT SKYBLUE (1325 4450);
FORCEPROP 1 LASTPIN (1125 4450) $PN 2
J 0
(1087 4462);
DISPLAY 0.617021 (1087 4462);
PAINT MONO (1087 4462);
FORCEPROP 1 LAST TOLERANCE 1%
J 0
(1150 4450);
DISPLAY 0.617021 (1150 4450);
PAINT SKYBLUE (1150 4450);
FORCEPROP 1 LAST LOCATION R2U10
J 0
(975 4500);
DISPLAY 0.617021 (975 4500);
PAINT AQUA (975 4500);
FORCEPROP 1 LASTPIN (925 4450) $PN 1
J 0
(937 4462);
DISPLAY 0.617021 (937 4462);
PAINT MONO (937 4462);
FORCEPROP 1 LAST MATERIAL CHIP
J 0
(825 4450);
DISPLAY 0.617021 (825 4450);
PAINT SKYBLUE (825 4450);
FORCEADD RES..1
(700 1600);
FORCEPROP 2 LAST CDS_SEC 1
J 0
(650 1800);
DISPLAY 1.404255 (650 1800);
PAINT ORANGE (650 1800);
DISPLAY INVISIBLE (650 1800);
FORCEPROP 2 LAST $SEC 1
J 0
(650 1800);
DISPLAY 0.936170 (650 1800);
PAINT MONO (650 1800);
DISPLAY INVISIBLE (650 1800);
FORCEPROP 2 LAST BOM_COST SM_CONTROLLER
J 0
(650 1750);
DISPLAY 1.021277 (650 1750);
PAINT ORANGE (650 1750);
DISPLAY INVISIBLE (650 1750);
FORCEPROP 1 LAST PATH I222
J 0
(650 1750);
DISPLAY 0.978723 (650 1750);
PAINT WHITE (650 1750);
DISPLAY INVISIBLE (650 1750);
FORCEPROP 2 LAST ROOM SMBUS
J 0
(650 1700);
DISPLAY 1.021277 (650 1700);
PAINT ORANGE (650 1700);
DISPLAY INVISIBLE (650 1700);
FORCEPROP 1 LAST PART_NUMBER G21497-005
J 0
(650 1675);
PAINT BLUE (650 1675);
DISPLAY INVISIBLE (650 1675);
FORCEPROP 2 LAST CDS_LOCATION R1U11
J 0
(650 1650);
DISPLAY 0.617021 (650 1650);
PAINT AQUA (650 1650);
DISPLAY INVISIBLE (650 1650);
FORCEPROP 2 LAST CDS_LIB mstr_discrete
J 0
(700 1600);
PAINT ORANGE (700 1600);
DISPLAY INVISIBLE (700 1600);
FORCEPROP 1 LAST PACK_TYPE 0402
J 0
(950 1450);
PAINT SKYBLUE (950 1450);
DISPLAY INVISIBLE (950 1450);
FORCEPROP 1 LAST WATTAGE 1/16W
J 2
(475 1600);
PAINT SKYBLUE (475 1600);
DISPLAY INVISIBLE (475 1600);
FORCEPROP 1 LAST TOLERANCE 5%
J 0
(825 1600);
DISPLAY 0.617021 (825 1600);
PAINT SKYBLUE (825 1600);
FORCEPROP 1 LAST VALUE 0.0
J 2
(1000 1600);
DISPLAY 0.617021 (1000 1600);
PAINT SKYBLUE (1000 1600);
FORCEPROP 1 LASTPIN (800 1600) $PN 2
J 0
(762 1612);
DISPLAY 0.617021 (762 1612);
PAINT MONO (762 1612);
FORCEPROP 1 LAST LOCATION R1U11
J 0
(650 1650);
DISPLAY 0.617021 (650 1650);
PAINT AQUA (650 1650);
FORCEPROP 1 LASTPIN (600 1600) $PN 1
J 0
(612 1612);
DISPLAY 0.617021 (612 1612);
PAINT MONO (612 1612);
FORCEPROP 1 LAST MATERIAL CHIP
J 0
(500 1600);
DISPLAY 0.617021 (500 1600);
PAINT SKYBLUE (500 1600);
FORCEADD RES..1
(700 1775);
FORCEPROP 1 LAST PACK_TYPE 0402
J 0
(950 1625);
PAINT SKYBLUE (950 1625);
DISPLAY INVISIBLE (950 1625);
FORCEPROP 2 LAST BOM_COST SM_CONTROLLER
J 0
(650 1925);
DISPLAY 1.021277 (650 1925);
PAINT ORANGE (650 1925);
DISPLAY INVISIBLE (650 1925);
FORCEPROP 2 LAST CDS_SEC 1
J 0
(650 1975);
DISPLAY 1.404255 (650 1975);
PAINT ORANGE (650 1975);
DISPLAY INVISIBLE (650 1975);
FORCEPROP 2 LAST $SEC 1
J 0
(650 1975);
DISPLAY 0.936170 (650 1975);
PAINT MONO (650 1975);
DISPLAY INVISIBLE (650 1975);
FORCEPROP 2 LAST CDS_LOCATION R1U8
J 0
(650 1825);
DISPLAY 0.617021 (650 1825);
PAINT AQUA (650 1825);
DISPLAY INVISIBLE (650 1825);
FORCEPROP 1 LAST PATH I223
J 0
(650 1925);
DISPLAY 0.978723 (650 1925);
PAINT WHITE (650 1925);
DISPLAY INVISIBLE (650 1925);
FORCEPROP 2 LAST ROOM SMBUS
J 0
(650 1875);
DISPLAY 1.021277 (650 1875);
PAINT ORANGE (650 1875);
DISPLAY INVISIBLE (650 1875);
FORCEPROP 1 LAST PART_NUMBER G21497-005
J 0
(650 1850);
PAINT BLUE (650 1850);
DISPLAY INVISIBLE (650 1850);
FORCEPROP 2 LAST CDS_LIB mstr_discrete
J 0
(700 1775);
PAINT ORANGE (700 1775);
DISPLAY INVISIBLE (700 1775);
FORCEPROP 1 LAST WATTAGE 1/16W
J 2
(475 1775);
PAINT SKYBLUE (475 1775);
DISPLAY INVISIBLE (475 1775);
FORCEPROP 1 LAST TOLERANCE 5%
J 0
(825 1775);
DISPLAY 0.617021 (825 1775);
PAINT SKYBLUE (825 1775);
FORCEPROP 1 LAST VALUE 0.0
J 2
(1000 1775);
DISPLAY 0.617021 (1000 1775);
PAINT SKYBLUE (1000 1775);
FORCEPROP 1 LASTPIN (800 1775) $PN 2
J 0
(762 1787);
DISPLAY 0.617021 (762 1787);
PAINT MONO (762 1787);
FORCEPROP 1 LAST LOCATION R1U8
J 0
(650 1825);
DISPLAY 0.617021 (650 1825);
PAINT AQUA (650 1825);
FORCEPROP 1 LASTPIN (600 1775) $PN 1
J 0
(612 1787);
DISPLAY 0.617021 (612 1787);
PAINT MONO (612 1787);
FORCEPROP 1 LAST MATERIAL CHIP
J 0
(500 1775);
DISPLAY 0.617021 (500 1775);
PAINT SKYBLUE (500 1775);
FORCEADD RES..1
(-3625 1575);
FORCEPROP 1 LAST PACK_TYPE 0402
J 0
(-3375 1425);
PAINT SKYBLUE (-3375 1425);
DISPLAY INVISIBLE (-3375 1425);
FORCEPROP 2 LAST CDS_SEC 1
J 0
(-3675 1775);
DISPLAY 1.404255 (-3675 1775);
PAINT ORANGE (-3675 1775);
DISPLAY INVISIBLE (-3675 1775);
FORCEPROP 2 LAST $SEC 1
J 0
(-3675 1775);
DISPLAY 0.936170 (-3675 1775);
PAINT MONO (-3675 1775);
DISPLAY INVISIBLE (-3675 1775);
FORCEPROP 1 LAST PATH I224
J 0
(-3675 1725);
DISPLAY 0.978723 (-3675 1725);
PAINT WHITE (-3675 1725);
DISPLAY INVISIBLE (-3675 1725);
FORCEPROP 2 LAST ROOM SMBUS
J 0
(-3675 1675);
DISPLAY 1.021277 (-3675 1675);
PAINT ORANGE (-3675 1675);
DISPLAY INVISIBLE (-3675 1675);
FORCEPROP 2 LAST BOM_COST SM_CONTROLLER
J 0
(-3675 1725);
DISPLAY 1.021277 (-3675 1725);
PAINT ORANGE (-3675 1725);
DISPLAY INVISIBLE (-3675 1725);
FORCEPROP 1 LAST PART_NUMBER G21796-173
J 0
(-3675 1650);
PAINT BLUE (-3675 1650);
DISPLAY INVISIBLE (-3675 1650);
FORCEPROP 2 LAST CDS_LIB mstr_discrete
J 0
(-3625 1575);
PAINT ORANGE (-3625 1575);
DISPLAY INVISIBLE (-3625 1575);
FORCEPROP 2 LAST CDS_LOCATION R9G12
J 0
(-3675 1625);
DISPLAY 0.617021 (-3675 1625);
PAINT AQUA (-3675 1625);
DISPLAY INVISIBLE (-3675 1625);
FORCEPROP 1 LAST WATTAGE 1/16W
J 2
(-3850 1575);
PAINT SKYBLUE (-3850 1575);
DISPLAY INVISIBLE (-3850 1575);
FORCEPROP 1 LASTPIN (-3525 1575) $PN 2
J 0
(-3563 1587);
DISPLAY 0.617021 (-3563 1587);
PAINT MONO (-3563 1587);
FORCEPROP 1 LAST TOLERANCE 1%
J 0
(-3500 1575);
DISPLAY 0.617021 (-3500 1575);
PAINT SKYBLUE (-3500 1575);
FORCEPROP 1 LAST VALUE 20.0
J 2
(-3325 1575);
DISPLAY 0.617021 (-3325 1575);
PAINT SKYBLUE (-3325 1575);
FORCEPROP 1 LAST LOCATION R9G12
J 0
(-3675 1625);
DISPLAY 0.617021 (-3675 1625);
PAINT AQUA (-3675 1625);
FORCEPROP 1 LAST MATERIAL CHIP
J 0
(-3825 1575);
DISPLAY 0.617021 (-3825 1575);
PAINT SKYBLUE (-3825 1575);
FORCEPROP 1 LASTPIN (-3725 1575) $PN 1
J 0
(-3713 1587);
DISPLAY 0.617021 (-3713 1587);
PAINT MONO (-3713 1587);
FORCEADD RES..1
(-3625 1450);
FORCEPROP 1 LAST PACK_TYPE 0402
J 0
(-3375 1300);
PAINT SKYBLUE (-3375 1300);
DISPLAY INVISIBLE (-3375 1300);
FORCEPROP 2 LAST CDS_SEC 1
J 0
(-3675 1650);
DISPLAY 1.404255 (-3675 1650);
PAINT ORANGE (-3675 1650);
DISPLAY INVISIBLE (-3675 1650);
FORCEPROP 2 LAST $SEC 1
J 0
(-3675 1650);
DISPLAY 0.936170 (-3675 1650);
PAINT MONO (-3675 1650);
DISPLAY INVISIBLE (-3675 1650);
FORCEPROP 2 LAST BOM_COST SM_CONTROLLER
J 0
(-3675 1600);
DISPLAY 1.021277 (-3675 1600);
PAINT ORANGE (-3675 1600);
DISPLAY INVISIBLE (-3675 1600);
FORCEPROP 1 LAST PATH I225
J 0
(-3675 1600);
DISPLAY 0.978723 (-3675 1600);
PAINT WHITE (-3675 1600);
DISPLAY INVISIBLE (-3675 1600);
FORCEPROP 2 LAST ROOM SMBUS
J 0
(-3675 1550);
DISPLAY 1.021277 (-3675 1550);
PAINT ORANGE (-3675 1550);
DISPLAY INVISIBLE (-3675 1550);
FORCEPROP 1 LAST PART_NUMBER G21796-173
J 0
(-3675 1525);
PAINT BLUE (-3675 1525);
DISPLAY INVISIBLE (-3675 1525);
FORCEPROP 2 LAST CDS_LIB mstr_discrete
J 0
(-3625 1450);
PAINT ORANGE (-3625 1450);
DISPLAY INVISIBLE (-3625 1450);
FORCEPROP 2 LAST CDS_LOCATION R1U20
J 0
(-3675 1500);
DISPLAY 0.617021 (-3675 1500);
PAINT AQUA (-3675 1500);
DISPLAY INVISIBLE (-3675 1500);
FORCEPROP 1 LAST WATTAGE 1/16W
J 2
(-3850 1450);
PAINT SKYBLUE (-3850 1450);
DISPLAY INVISIBLE (-3850 1450);
FORCEPROP 1 LAST VALUE 20.0
J 2
(-3325 1450);
DISPLAY 0.617021 (-3325 1450);
PAINT SKYBLUE (-3325 1450);
FORCEPROP 1 LASTPIN (-3525 1450) $PN 2
J 0
(-3563 1462);
DISPLAY 0.617021 (-3563 1462);
PAINT MONO (-3563 1462);
FORCEPROP 1 LAST TOLERANCE 1%
J 0
(-3500 1450);
DISPLAY 0.617021 (-3500 1450);
PAINT SKYBLUE (-3500 1450);
FORCEPROP 1 LAST LOCATION R1U20
J 0
(-3675 1500);
DISPLAY 0.617021 (-3675 1500);
PAINT AQUA (-3675 1500);
FORCEPROP 1 LASTPIN (-3725 1450) $PN 1
J 0
(-3713 1462);
DISPLAY 0.617021 (-3713 1462);
PAINT MONO (-3713 1462);
FORCEPROP 1 LAST MATERIAL CHIP
J 0
(-3825 1450);
DISPLAY 0.617021 (-3825 1450);
PAINT SKYBLUE (-3825 1450);
FORCEADD RES..1
(-3625 1325);
FORCEPROP 1 LAST PACK_TYPE 0402
J 0
(-3375 1175);
PAINT SKYBLUE (-3375 1175);
DISPLAY INVISIBLE (-3375 1175);
FORCEPROP 2 LAST CDS_SEC 1
J 0
(-3675 1525);
DISPLAY 1.404255 (-3675 1525);
PAINT ORANGE (-3675 1525);
DISPLAY INVISIBLE (-3675 1525);
FORCEPROP 2 LAST $SEC 1
J 0
(-3675 1525);
DISPLAY 0.936170 (-3675 1525);
PAINT MONO (-3675 1525);
DISPLAY INVISIBLE (-3675 1525);
FORCEPROP 2 LAST BOM_COST SM_CONTROLLER
J 0
(-3675 1475);
DISPLAY 1.021277 (-3675 1475);
PAINT ORANGE (-3675 1475);
DISPLAY INVISIBLE (-3675 1475);
FORCEPROP 1 LAST PATH I226
J 0
(-3675 1475);
DISPLAY 0.978723 (-3675 1475);
PAINT WHITE (-3675 1475);
DISPLAY INVISIBLE (-3675 1475);
FORCEPROP 2 LAST ROOM SMBUS
J 0
(-3675 1425);
DISPLAY 1.021277 (-3675 1425);
PAINT ORANGE (-3675 1425);
DISPLAY INVISIBLE (-3675 1425);
FORCEPROP 1 LAST PART_NUMBER G21796-173
J 0
(-3675 1400);
PAINT BLUE (-3675 1400);
DISPLAY INVISIBLE (-3675 1400);
FORCEPROP 2 LAST CDS_LIB mstr_discrete
J 0
(-3625 1325);
PAINT ORANGE (-3625 1325);
DISPLAY INVISIBLE (-3625 1325);
FORCEPROP 2 LAST CDS_LOCATION R1U19
J 0
(-3675 1375);
DISPLAY 0.617021 (-3675 1375);
PAINT AQUA (-3675 1375);
DISPLAY INVISIBLE (-3675 1375);
FORCEPROP 1 LAST WATTAGE 1/16W
J 2
(-3850 1325);
PAINT SKYBLUE (-3850 1325);
DISPLAY INVISIBLE (-3850 1325);
FORCEPROP 1 LAST VALUE 20.0
J 2
(-3325 1325);
DISPLAY 0.617021 (-3325 1325);
PAINT SKYBLUE (-3325 1325);
FORCEPROP 1 LAST TOLERANCE 1%
J 0
(-3500 1325);
DISPLAY 0.617021 (-3500 1325);
PAINT SKYBLUE (-3500 1325);
FORCEPROP 1 LASTPIN (-3525 1325) $PN 2
J 0
(-3563 1337);
DISPLAY 0.617021 (-3563 1337);
PAINT MONO (-3563 1337);
FORCEPROP 1 LAST LOCATION R1U19
J 0
(-3675 1375);
DISPLAY 0.617021 (-3675 1375);
PAINT AQUA (-3675 1375);
FORCEPROP 1 LASTPIN (-3725 1325) $PN 1
J 0
(-3713 1337);
DISPLAY 0.617021 (-3713 1337);
PAINT MONO (-3713 1337);
FORCEPROP 1 LAST MATERIAL CHIP
J 0
(-3825 1325);
DISPLAY 0.617021 (-3825 1325);
PAINT SKYBLUE (-3825 1325);
FORCEADD RES..1
(-3625 1200);
FORCEPROP 1 LAST PACK_TYPE 0402
J 0
(-3375 1050);
PAINT SKYBLUE (-3375 1050);
DISPLAY INVISIBLE (-3375 1050);
FORCEPROP 2 LAST CDS_SEC 1
J 0
(-3675 1400);
DISPLAY 1.404255 (-3675 1400);
PAINT ORANGE (-3675 1400);
DISPLAY INVISIBLE (-3675 1400);
FORCEPROP 2 LAST $SEC 1
J 0
(-3675 1400);
DISPLAY 0.936170 (-3675 1400);
PAINT MONO (-3675 1400);
DISPLAY INVISIBLE (-3675 1400);
FORCEPROP 2 LAST ROOM SMBUS
J 0
(-3675 1300);
DISPLAY 1.021277 (-3675 1300);
PAINT ORANGE (-3675 1300);
DISPLAY INVISIBLE (-3675 1300);
FORCEPROP 1 LAST PATH I227
J 0
(-3675 1350);
DISPLAY 0.978723 (-3675 1350);
PAINT WHITE (-3675 1350);
DISPLAY INVISIBLE (-3675 1350);
FORCEPROP 2 LAST BOM_COST SM_CONTROLLER
J 0
(-3675 1350);
DISPLAY 1.021277 (-3675 1350);
PAINT ORANGE (-3675 1350);
DISPLAY INVISIBLE (-3675 1350);
FORCEPROP 1 LAST PART_NUMBER G21796-173
J 0
(-3675 1275);
PAINT BLUE (-3675 1275);
DISPLAY INVISIBLE (-3675 1275);
FORCEPROP 2 LAST CDS_LIB mstr_discrete
J 0
(-3625 1200);
PAINT ORANGE (-3625 1200);
DISPLAY INVISIBLE (-3625 1200);
FORCEPROP 2 LAST CDS_LOCATION R9G13
J 0
(-3675 1250);
DISPLAY 0.617021 (-3675 1250);
PAINT AQUA (-3675 1250);
DISPLAY INVISIBLE (-3675 1250);
FORCEPROP 1 LAST WATTAGE 1/16W
J 2
(-3850 1200);
PAINT SKYBLUE (-3850 1200);
DISPLAY INVISIBLE (-3850 1200);
FORCEPROP 1 LAST VALUE 20.0
J 2
(-3325 1200);
DISPLAY 0.617021 (-3325 1200);
PAINT SKYBLUE (-3325 1200);
FORCEPROP 1 LAST TOLERANCE 1%
J 0
(-3500 1200);
DISPLAY 0.617021 (-3500 1200);
PAINT SKYBLUE (-3500 1200);
FORCEPROP 1 LASTPIN (-3525 1200) $PN 2
J 0
(-3563 1212);
DISPLAY 0.617021 (-3563 1212);
PAINT MONO (-3563 1212);
FORCEPROP 1 LAST LOCATION R9G13
J 0
(-3675 1250);
DISPLAY 0.617021 (-3675 1250);
PAINT AQUA (-3675 1250);
FORCEPROP 1 LASTPIN (-3725 1200) $PN 1
J 0
(-3713 1212);
DISPLAY 0.617021 (-3713 1212);
PAINT MONO (-3713 1212);
FORCEPROP 1 LAST MATERIAL CHIP
J 0
(-3825 1200);
DISPLAY 0.617021 (-3825 1200);
PAINT SKYBLUE (-3825 1200);
FORCEADD RES..1
(-2875 2525);
FORCEPROP 2 LAST BOM_COST SM_CONTROLLER
J 0
(-2925 2675);
DISPLAY 1.021277 (-2925 2675);
PAINT ORANGE (-2925 2675);
DISPLAY INVISIBLE (-2925 2675);
FORCEPROP 2 LAST CDS_SEC 1
J 0
(-2925 2725);
DISPLAY 1.404255 (-2925 2725);
PAINT ORANGE (-2925 2725);
DISPLAY INVISIBLE (-2925 2725);
FORCEPROP 2 LAST $SEC 1
J 0
(-2925 2725);
DISPLAY 0.936170 (-2925 2725);
PAINT MONO (-2925 2725);
DISPLAY INVISIBLE (-2925 2725);
FORCEPROP 2 LAST CDS_LOCATION R8G5
J 0
(-2925 2575);
DISPLAY 0.617021 (-2925 2575);
PAINT AQUA (-2925 2575);
DISPLAY INVISIBLE (-2925 2575);
FORCEPROP 1 LAST PATH I228
J 0
(-2925 2675);
DISPLAY 0.978723 (-2925 2675);
PAINT WHITE (-2925 2675);
DISPLAY INVISIBLE (-2925 2675);
FORCEPROP 2 LAST ROOM SMBUS
J 0
(-2925 2625);
DISPLAY 1.021277 (-2925 2625);
PAINT ORANGE (-2925 2625);
DISPLAY INVISIBLE (-2925 2625);
FORCEPROP 1 LAST PART_NUMBER G21796-173
J 0
(-2925 2600);
PAINT BLUE (-2925 2600);
DISPLAY INVISIBLE (-2925 2600);
FORCEPROP 2 LAST CDS_LIB mstr_discrete
J 0
(-2875 2525);
PAINT ORANGE (-2875 2525);
DISPLAY INVISIBLE (-2875 2525);
FORCEPROP 1 LAST PACK_TYPE 0402
J 0
(-2625 2375);
PAINT SKYBLUE (-2625 2375);
DISPLAY INVISIBLE (-2625 2375);
FORCEPROP 1 LAST WATTAGE 1/16W
J 2
(-3100 2525);
PAINT SKYBLUE (-3100 2525);
DISPLAY INVISIBLE (-3100 2525);
FORCEPROP 1 LAST LOCATION R8G5
J 0
(-2925 2575);
DISPLAY 0.617021 (-2925 2575);
PAINT AQUA (-2925 2575);
FORCEPROP 1 LASTPIN (-2775 2525) $PN 2
J 0
(-2813 2537);
DISPLAY 0.617021 (-2813 2537);
PAINT MONO (-2813 2537);
FORCEPROP 1 LASTPIN (-2975 2525) $PN 1
J 0
(-2963 2537);
DISPLAY 0.617021 (-2963 2537);
PAINT MONO (-2963 2537);
FORCEPROP 1 LAST TOLERANCE 1%
J 0
(-2750 2525);
DISPLAY 0.617021 (-2750 2525);
PAINT SKYBLUE (-2750 2525);
FORCEPROP 1 LAST VALUE 20.0
J 2
(-2575 2525);
DISPLAY 0.617021 (-2575 2525);
PAINT SKYBLUE (-2575 2525);
FORCEPROP 1 LAST MATERIAL CHIP
J 0
(-3075 2525);
DISPLAY 0.617021 (-3075 2525);
PAINT SKYBLUE (-3075 2525);
FORCEADD RES..1
(-2875 2350);
FORCEPROP 2 LAST CDS_SEC 1
J 0
(-2925 2550);
DISPLAY 1.404255 (-2925 2550);
PAINT ORANGE (-2925 2550);
DISPLAY INVISIBLE (-2925 2550);
FORCEPROP 2 LAST $SEC 1
J 0
(-2925 2550);
DISPLAY 0.936170 (-2925 2550);
PAINT MONO (-2925 2550);
DISPLAY INVISIBLE (-2925 2550);
FORCEPROP 1 LAST PACK_TYPE 0402
J 0
(-2625 2200);
PAINT SKYBLUE (-2625 2200);
DISPLAY INVISIBLE (-2625 2200);
FORCEPROP 2 LAST BOM_COST SM_CONTROLLER
J 0
(-2925 2500);
DISPLAY 1.021277 (-2925 2500);
PAINT ORANGE (-2925 2500);
DISPLAY INVISIBLE (-2925 2500);
FORCEPROP 1 LAST PATH I229
J 0
(-2925 2500);
DISPLAY 0.978723 (-2925 2500);
PAINT WHITE (-2925 2500);
DISPLAY INVISIBLE (-2925 2500);
FORCEPROP 2 LAST ROOM SMBUS
J 0
(-2925 2450);
DISPLAY 1.021277 (-2925 2450);
PAINT ORANGE (-2925 2450);
DISPLAY INVISIBLE (-2925 2450);
FORCEPROP 1 LAST PART_NUMBER G21796-173
J 0
(-2925 2425);
PAINT BLUE (-2925 2425);
DISPLAY INVISIBLE (-2925 2425);
FORCEPROP 2 LAST CDS_LIB mstr_discrete
J 0
(-2875 2350);
PAINT ORANGE (-2875 2350);
DISPLAY INVISIBLE (-2875 2350);
FORCEPROP 2 LAST CDS_LOCATION R8G4
J 0
(-2925 2400);
DISPLAY 0.617021 (-2925 2400);
PAINT AQUA (-2925 2400);
DISPLAY INVISIBLE (-2925 2400);
FORCEPROP 1 LAST WATTAGE 1/16W
J 2
(-3100 2350);
PAINT SKYBLUE (-3100 2350);
DISPLAY INVISIBLE (-3100 2350);
FORCEPROP 1 LASTPIN (-2775 2350) $PN 2
J 0
(-2813 2362);
DISPLAY 0.617021 (-2813 2362);
PAINT MONO (-2813 2362);
FORCEPROP 1 LAST TOLERANCE 1%
J 0
(-2750 2350);
DISPLAY 0.617021 (-2750 2350);
PAINT SKYBLUE (-2750 2350);
FORCEPROP 1 LAST VALUE 20.0
J 2
(-2575 2350);
DISPLAY 0.617021 (-2575 2350);
PAINT SKYBLUE (-2575 2350);
FORCEPROP 1 LAST LOCATION R8G4
J 0
(-2925 2400);
DISPLAY 0.617021 (-2925 2400);
PAINT AQUA (-2925 2400);
FORCEPROP 1 LASTPIN (-2975 2350) $PN 1
J 0
(-2963 2362);
DISPLAY 0.617021 (-2963 2362);
PAINT MONO (-2963 2362);
FORCEPROP 1 LAST MATERIAL CHIP
J 0
(-3075 2350);
DISPLAY 0.617021 (-3075 2350);
PAINT SKYBLUE (-3075 2350);
FORCEADD RES..1
(-3175 3600);
FORCEPROP 1 LAST PACK_TYPE 0402
J 0
(-2925 3450);
PAINT SKYBLUE (-2925 3450);
DISPLAY INVISIBLE (-2925 3450);
FORCEPROP 2 LAST CDS_SEC 1
J 0
(-3225 3800);
DISPLAY 1.404255 (-3225 3800);
PAINT ORANGE (-3225 3800);
DISPLAY INVISIBLE (-3225 3800);
FORCEPROP 2 LAST CDS_LIB mstr_discrete
J 0
(-3175 3600);
PAINT ORANGE (-3175 3600);
DISPLAY INVISIBLE (-3175 3600);
FORCEPROP 2 LAST BOM_COST SM_CONTROLLER
J 0
(-3225 3750);
DISPLAY 1.021277 (-3225 3750);
PAINT ORANGE (-3225 3750);
DISPLAY INVISIBLE (-3225 3750);
FORCEPROP 2 LAST $SEC 1
J 0
(-3225 3800);
DISPLAY 0.936170 (-3225 3800);
PAINT MONO (-3225 3800);
DISPLAY INVISIBLE (-3225 3800);
FORCEPROP 2 LAST CDS_LOCATION R2U34
J 0
(-3225 3650);
DISPLAY 0.617021 (-3225 3650);
PAINT AQUA (-3225 3650);
DISPLAY INVISIBLE (-3225 3650);
FORCEPROP 1 LAST PATH I230
J 0
(-3225 3750);
DISPLAY 0.978723 (-3225 3750);
PAINT WHITE (-3225 3750);
DISPLAY INVISIBLE (-3225 3750);
FORCEPROP 2 LAST ROOM SMBUS
J 0
(-3225 3700);
DISPLAY 1.021277 (-3225 3700);
PAINT ORANGE (-3225 3700);
DISPLAY INVISIBLE (-3225 3700);
FORCEPROP 1 LAST PART_NUMBER G21796-173
J 0
(-3225 3675);
PAINT BLUE (-3225 3675);
DISPLAY INVISIBLE (-3225 3675);
FORCEPROP 1 LAST WATTAGE 1/16W
J 2
(-3400 3600);
PAINT SKYBLUE (-3400 3600);
DISPLAY INVISIBLE (-3400 3600);
FORCEPROP 1 LAST TOLERANCE 1%
J 0
(-3050 3600);
DISPLAY 0.617021 (-3050 3600);
PAINT SKYBLUE (-3050 3600);
FORCEPROP 1 LAST VALUE 20.0
J 2
(-2875 3600);
DISPLAY 0.617021 (-2875 3600);
PAINT SKYBLUE (-2875 3600);
FORCEPROP 1 LASTPIN (-3075 3600) $PN 2
J 0
(-3113 3612);
DISPLAY 0.617021 (-3113 3612);
PAINT MONO (-3113 3612);
FORCEPROP 1 LAST LOCATION R2U34
J 0
(-3225 3650);
DISPLAY 0.617021 (-3225 3650);
PAINT AQUA (-3225 3650);
FORCEPROP 1 LASTPIN (-3275 3600) $PN 1
J 0
(-3263 3612);
DISPLAY 0.617021 (-3263 3612);
PAINT MONO (-3263 3612);
FORCEPROP 1 LAST MATERIAL CHIP
J 0
(-3375 3600);
DISPLAY 0.617021 (-3375 3600);
PAINT SKYBLUE (-3375 3600);
FORCEADD RES..1
(-3175 3775);
FORCEPROP 1 LAST PACK_TYPE 0402
J 0
(-2925 3625);
PAINT SKYBLUE (-2925 3625);
DISPLAY INVISIBLE (-2925 3625);
FORCEPROP 2 LAST BOM_COST SM_CONTROLLER
J 0
(-3225 3925);
DISPLAY 1.021277 (-3225 3925);
PAINT ORANGE (-3225 3925);
DISPLAY INVISIBLE (-3225 3925);
FORCEPROP 2 LAST CDS_SEC 1
J 0
(-3225 3975);
DISPLAY 1.404255 (-3225 3975);
PAINT ORANGE (-3225 3975);
DISPLAY INVISIBLE (-3225 3975);
FORCEPROP 2 LAST $SEC 1
J 0
(-3225 3975);
DISPLAY 0.936170 (-3225 3975);
PAINT MONO (-3225 3975);
DISPLAY INVISIBLE (-3225 3975);
FORCEPROP 1 LAST PATH I231
J 0
(-3225 3925);
DISPLAY 0.978723 (-3225 3925);
PAINT WHITE (-3225 3925);
DISPLAY INVISIBLE (-3225 3925);
FORCEPROP 2 LAST ROOM SMBUS
J 0
(-3225 3875);
DISPLAY 1.021277 (-3225 3875);
PAINT ORANGE (-3225 3875);
DISPLAY INVISIBLE (-3225 3875);
FORCEPROP 1 LAST PART_NUMBER G21796-173
J 0
(-3225 3850);
PAINT BLUE (-3225 3850);
DISPLAY INVISIBLE (-3225 3850);
FORCEPROP 2 LAST CDS_LOCATION R2U33
J 0
(-3225 3825);
DISPLAY 0.617021 (-3225 3825);
PAINT AQUA (-3225 3825);
DISPLAY INVISIBLE (-3225 3825);
FORCEPROP 2 LAST CDS_LIB mstr_discrete
J 0
(-3175 3775);
PAINT ORANGE (-3175 3775);
DISPLAY INVISIBLE (-3175 3775);
FORCEPROP 1 LAST WATTAGE 1/16W
J 2
(-3400 3775);
PAINT SKYBLUE (-3400 3775);
DISPLAY INVISIBLE (-3400 3775);
FORCEPROP 1 LAST TOLERANCE 1%
J 0
(-3050 3775);
DISPLAY 0.617021 (-3050 3775);
PAINT SKYBLUE (-3050 3775);
FORCEPROP 1 LAST VALUE 20.0
J 2
(-2875 3775);
DISPLAY 0.617021 (-2875 3775);
PAINT SKYBLUE (-2875 3775);
FORCEPROP 1 LAST LOCATION R2U33
J 0
(-3225 3825);
DISPLAY 0.617021 (-3225 3825);
PAINT AQUA (-3225 3825);
FORCEPROP 1 LASTPIN (-3075 3775) $PN 2
J 0
(-3113 3787);
DISPLAY 0.617021 (-3113 3787);
PAINT MONO (-3113 3787);
FORCEPROP 1 LASTPIN (-3275 3775) $PN 1
J 0
(-3263 3787);
DISPLAY 0.617021 (-3263 3787);
PAINT MONO (-3263 3787);
FORCEPROP 1 LAST MATERIAL CHIP
J 0
(-3375 3775);
DISPLAY 0.617021 (-3375 3775);
PAINT SKYBLUE (-3375 3775);
FORCEADD RES..1
(-3175 4200);
FORCEPROP 2 LAST CDS_SEC 1
J 0
(-3225 4400);
DISPLAY 1.404255 (-3225 4400);
PAINT ORANGE (-3225 4400);
DISPLAY INVISIBLE (-3225 4400);
FORCEPROP 2 LAST $SEC 1
J 0
(-3225 4400);
DISPLAY 0.936170 (-3225 4400);
PAINT MONO (-3225 4400);
DISPLAY INVISIBLE (-3225 4400);
FORCEPROP 2 LAST BOM_COST SM_CONTROLLER
J 0
(-3225 4350);
DISPLAY 1.021277 (-3225 4350);
PAINT ORANGE (-3225 4350);
DISPLAY INVISIBLE (-3225 4350);
FORCEPROP 1 LAST PATH I232
J 0
(-3225 4350);
DISPLAY 0.978723 (-3225 4350);
PAINT WHITE (-3225 4350);
DISPLAY INVISIBLE (-3225 4350);
FORCEPROP 2 LAST CDS_LIB mstr_discrete
J 0
(-3175 4200);
PAINT ORANGE (-3175 4200);
DISPLAY INVISIBLE (-3175 4200);
FORCEPROP 1 LAST PART_NUMBER G21796-173
J 0
(-3225 4275);
PAINT BLUE (-3225 4275);
DISPLAY INVISIBLE (-3225 4275);
FORCEPROP 2 LAST CDS_LOCATION R1U9
J 0
(-3225 4250);
DISPLAY 0.617021 (-3225 4250);
PAINT AQUA (-3225 4250);
DISPLAY INVISIBLE (-3225 4250);
FORCEPROP 2 LAST ROOM SMBUS
J 0
(-3225 4300);
DISPLAY 1.021277 (-3225 4300);
PAINT ORANGE (-3225 4300);
DISPLAY INVISIBLE (-3225 4300);
FORCEPROP 1 LAST WATTAGE 1/16W
J 2
(-3400 4200);
PAINT SKYBLUE (-3400 4200);
DISPLAY INVISIBLE (-3400 4200);
FORCEPROP 1 LAST PACK_TYPE 0402
J 0
(-2925 4050);
PAINT SKYBLUE (-2925 4050);
DISPLAY INVISIBLE (-2925 4050);
FORCEPROP 1 LAST TOLERANCE 1%
J 0
(-3050 4200);
DISPLAY 0.617021 (-3050 4200);
PAINT SKYBLUE (-3050 4200);
FORCEPROP 1 LAST VALUE 20.0
J 2
(-2875 4200);
DISPLAY 0.617021 (-2875 4200);
PAINT SKYBLUE (-2875 4200);
FORCEPROP 1 LASTPIN (-3075 4200) $PN 2
J 0
(-3113 4212);
DISPLAY 0.617021 (-3113 4212);
PAINT MONO (-3113 4212);
FORCEPROP 1 LAST LOCATION R1U9
J 0
(-3225 4250);
DISPLAY 0.617021 (-3225 4250);
PAINT AQUA (-3225 4250);
FORCEPROP 1 LASTPIN (-3275 4200) $PN 1
J 0
(-3263 4212);
DISPLAY 0.617021 (-3263 4212);
PAINT MONO (-3263 4212);
FORCEPROP 1 LAST MATERIAL CHIP
J 0
(-3375 4200);
DISPLAY 0.617021 (-3375 4200);
PAINT SKYBLUE (-3375 4200);
FORCEADD RES..1
(-3175 4375);
FORCEPROP 1 LAST PACK_TYPE 0402
J 0
(-2925 4225);
PAINT SKYBLUE (-2925 4225);
DISPLAY INVISIBLE (-2925 4225);
FORCEPROP 2 LAST CDS_SEC 1
J 0
(-3225 4575);
DISPLAY 1.404255 (-3225 4575);
PAINT ORANGE (-3225 4575);
DISPLAY INVISIBLE (-3225 4575);
FORCEPROP 2 LAST $SEC 1
J 0
(-3225 4575);
DISPLAY 0.936170 (-3225 4575);
PAINT MONO (-3225 4575);
DISPLAY INVISIBLE (-3225 4575);
FORCEPROP 2 LAST CDS_LIB mstr_discrete
J 0
(-3175 4375);
PAINT ORANGE (-3175 4375);
DISPLAY INVISIBLE (-3175 4375);
FORCEPROP 2 LAST ROOM SMBUS
J 0
(-3225 4475);
DISPLAY 1.021277 (-3225 4475);
PAINT ORANGE (-3225 4475);
DISPLAY INVISIBLE (-3225 4475);
FORCEPROP 1 LAST PATH I233
J 0
(-3225 4525);
DISPLAY 0.978723 (-3225 4525);
PAINT WHITE (-3225 4525);
DISPLAY INVISIBLE (-3225 4525);
FORCEPROP 2 LAST BOM_COST SM_CONTROLLER
J 0
(-3225 4525);
DISPLAY 1.021277 (-3225 4525);
PAINT ORANGE (-3225 4525);
DISPLAY INVISIBLE (-3225 4525);
FORCEPROP 2 LAST CDS_LOCATION R1U10
J 0
(-3225 4425);
DISPLAY 0.617021 (-3225 4425);
PAINT AQUA (-3225 4425);
DISPLAY INVISIBLE (-3225 4425);
FORCEPROP 1 LAST PART_NUMBER G21796-173
J 0
(-3225 4450);
PAINT BLUE (-3225 4450);
DISPLAY INVISIBLE (-3225 4450);
FORCEPROP 1 LAST WATTAGE 1/16W
J 2
(-3400 4375);
PAINT SKYBLUE (-3400 4375);
DISPLAY INVISIBLE (-3400 4375);
FORCEPROP 1 LAST TOLERANCE 1%
J 0
(-3050 4375);
DISPLAY 0.617021 (-3050 4375);
PAINT SKYBLUE (-3050 4375);
FORCEPROP 1 LAST VALUE 20.0
J 2
(-2875 4375);
DISPLAY 0.617021 (-2875 4375);
PAINT SKYBLUE (-2875 4375);
FORCEPROP 1 LASTPIN (-3075 4375) $PN 2
J 0
(-3113 4387);
DISPLAY 0.617021 (-3113 4387);
PAINT MONO (-3113 4387);
FORCEPROP 1 LAST LOCATION R1U10
J 0
(-3225 4425);
DISPLAY 0.617021 (-3225 4425);
PAINT AQUA (-3225 4425);
FORCEPROP 1 LASTPIN (-3275 4375) $PN 1
J 0
(-3263 4387);
DISPLAY 0.617021 (-3263 4387);
PAINT MONO (-3263 4387);
FORCEPROP 1 LAST MATERIAL CHIP
J 0
(-3375 4375);
DISPLAY 0.617021 (-3375 4375);
PAINT SKYBLUE (-3375 4375);
FORCEADD OFFPAGE..2
(1875 4275);
FORCEPROP 2 LAST PATH I75
J 0
(2200 4325);
DISPLAY 1.021277 (2200 4325);
PAINT ORANGE (2200 4325);
DISPLAY INVISIBLE (2200 4325);
FORCEPROP 1 LAST OFFPAGE TRUE
J 0
(2200 4150);
DISPLAY 0.872340 (2200 4150);
PAINT GREEN (2200 4150);
DISPLAY INVISIBLE (2200 4150);
FORCEPROP 1 LAST COMMENT_BODY TRUE
J 0
(1830 4180);
DISPLAY 0.872340 (1830 4180);
PAINT GREEN (1830 4180);
DISPLAY INVISIBLE (1830 4180);
FORCEPROP 2 LAST CDS_LIB mstr_standard
J 0
(1875 4275);
PAINT ORANGE (1875 4275);
DISPLAY INVISIBLE (1875 4275);
FORCEPROP 2 LAST $XR3 188 
J 0
(2394 4275);
DISPLAY 0.638298 (2394 4275);
PAINT MONO (2394 4275);
FORCEPROP 2 LAST $XR2 186 
J 0
(2274 4275);
DISPLAY 0.638298 (2274 4275);
PAINT MONO (2274 4275);
FORCEPROP 2 LAST $XR1 91 
J 0
(2184 4275);
DISPLAY 0.638298 (2184 4275);
PAINT MONO (2184 4275);
FORCEPROP 2 LAST $XR0 138 
J 0
(2064 4275);
DISPLAY 0.638298 (2064 4275);
PAINT MONO (2064 4275);
FORCEADD OFFPAGE..2
(1875 3375);
FORCEPROP 2 LAST PATH I76
J 0
(2200 3425);
DISPLAY 1.021277 (2200 3425);
PAINT ORANGE (2200 3425);
DISPLAY INVISIBLE (2200 3425);
FORCEPROP 1 LAST OFFPAGE TRUE
J 0
(2200 3250);
DISPLAY 0.872340 (2200 3250);
PAINT GREEN (2200 3250);
DISPLAY INVISIBLE (2200 3250);
FORCEPROP 2 LAST CDS_LIB mstr_standard
J 0
(1875 3375);
PAINT ORANGE (1875 3375);
DISPLAY INVISIBLE (1875 3375);
FORCEPROP 1 LAST COMMENT_BODY TRUE
J 0
(1830 3280);
DISPLAY 0.872340 (1830 3280);
PAINT GREEN (1830 3280);
DISPLAY INVISIBLE (1830 3280);
FORCEPROP 2 LAST $XR3 199 
J 0
(2304 3375);
DISPLAY 0.638298 (2304 3375);
PAINT MONO (2304 3375);
FORCEPROP 2 LAST $XR2 247 
J 0
(2304 3375);
DISPLAY 0.638298 (2304 3375);
PAINT MONO (2304 3375);
FORCEPROP 2 LAST $XR1 181 
J 0
(2184 3375);
DISPLAY 0.638298 (2184 3375);
PAINT MONO (2184 3375);
FORCEPROP 2 LAST $XR0 138 
J 0
(2064 3375);
DISPLAY 0.638298 (2064 3375);
PAINT MONO (2064 3375);
FORCEADD OFFPAGE..3
(1875 4450);
FORCEPROP 2 LAST PATH I77
J 0
(2225 4500);
DISPLAY 1.021277 (2225 4500);
PAINT ORANGE (2225 4500);
DISPLAY INVISIBLE (2225 4500);
FORCEPROP 1 LAST OFFPAGE TRUE
J 0
(2200 4325);
DISPLAY 0.872340 (2200 4325);
PAINT GREEN (2200 4325);
DISPLAY INVISIBLE (2200 4325);
FORCEPROP 2 LAST CDS_LIB mstr_standard
J 0
(1875 4450);
PAINT ORANGE (1875 4450);
DISPLAY INVISIBLE (1875 4450);
FORCEPROP 1 LAST COMMENT_BODY TRUE
J 0
(1825 4350);
DISPLAY 0.872340 (1825 4350);
PAINT GREEN (1825 4350);
DISPLAY INVISIBLE (1825 4350);
FORCEPROP 2 LAST $XR3 188 
J 0
(2419 4450);
DISPLAY 0.638298 (2419 4450);
PAINT MONO (2419 4450);
FORCEPROP 2 LAST $XR2 186 
J 0
(2299 4450);
DISPLAY 0.638298 (2299 4450);
PAINT MONO (2299 4450);
FORCEPROP 2 LAST $XR1 138 
J 0
(2179 4450);
DISPLAY 0.638298 (2179 4450);
PAINT MONO (2179 4450);
FORCEPROP 2 LAST $XR0 91 
J 0
(2089 4450);
DISPLAY 0.638298 (2089 4450);
PAINT MONO (2089 4450);
FORCEADD OFFPAGE..3
(1875 3550);
FORCEPROP 2 LAST PATH I78
J 0
(2225 3600);
DISPLAY 1.021277 (2225 3600);
PAINT ORANGE (2225 3600);
DISPLAY INVISIBLE (2225 3600);
FORCEPROP 1 LAST OFFPAGE TRUE
J 0
(2200 3425);
DISPLAY 0.872340 (2200 3425);
PAINT GREEN (2200 3425);
DISPLAY INVISIBLE (2200 3425);
FORCEPROP 2 LAST CDS_LIB mstr_standard
J 0
(1875 3550);
PAINT ORANGE (1875 3550);
DISPLAY INVISIBLE (1875 3550);
FORCEPROP 1 LAST COMMENT_BODY TRUE
J 0
(1825 3450);
DISPLAY 0.872340 (1825 3450);
PAINT GREEN (1825 3450);
DISPLAY INVISIBLE (1825 3450);
FORCEPROP 2 LAST $XR3 247 
J 0
(2329 3550);
DISPLAY 0.638298 (2329 3550);
PAINT MONO (2329 3550);
FORCEPROP 2 LAST $XR2 199 
J 0
(2329 3550);
DISPLAY 0.638298 (2329 3550);
PAINT MONO (2329 3550);
FORCEPROP 2 LAST $XR1 181 
J 0
(2209 3550);
DISPLAY 0.638298 (2209 3550);
PAINT MONO (2209 3550);
FORCEPROP 2 LAST $XR0 138 
J 0
(2089 3550);
DISPLAY 0.638298 (2089 3550);
PAINT MONO (2089 3550);
FORCEADD OFFPAGE..3
(1875 1775);
FORCEPROP 2 LAST PATH I79
J 0
(2225 1825);
DISPLAY 1.021277 (2225 1825);
PAINT ORANGE (2225 1825);
DISPLAY INVISIBLE (2225 1825);
FORCEPROP 1 LAST OFFPAGE TRUE
J 0
(2200 1650);
DISPLAY 0.872340 (2200 1650);
PAINT GREEN (2200 1650);
DISPLAY INVISIBLE (2200 1650);
FORCEPROP 2 LAST CDS_LIB mstr_standard
J 0
(1875 1775);
PAINT ORANGE (1875 1775);
DISPLAY INVISIBLE (1875 1775);
FORCEPROP 1 LAST COMMENT_BODY TRUE
J 0
(1825 1675);
DISPLAY 0.872340 (1825 1675);
PAINT GREEN (1825 1675);
DISPLAY INVISIBLE (1825 1675);
FORCEPROP 2 LAST $XR11 235 
J 0
(2449 1811);
DISPLAY 0.638298 (2449 1811);
PAINT MONO (2449 1811);
FORCEPROP 2 LAST $XR10 226 
J 0
(2329 1811);
DISPLAY 0.638298 (2329 1811);
PAINT MONO (2329 1811);
FORCEPROP 2 LAST $XR9 223 
J 0
(2209 1811);
DISPLAY 0.638298 (2209 1811);
PAINT MONO (2209 1811);
FORCEPROP 2 LAST $XR8 218 
J 0
(2089 1811);
DISPLAY 0.638298 (2089 1811);
PAINT MONO (2089 1811);
FORCEPROP 2 LAST $XR7 215 
J 0
(2449 1739);
DISPLAY 0.638298 (2449 1739);
PAINT MONO (2449 1739);
FORCEPROP 2 LAST $XR6 213 
J 0
(2329 1739);
DISPLAY 0.638298 (2329 1739);
PAINT MONO (2329 1739);
FORCEPROP 2 LAST $XR5 211 
J 0
(2209 1739);
DISPLAY 0.638298 (2209 1739);
PAINT MONO (2209 1739);
FORCEPROP 2 LAST $XR4 206 
J 0
(2089 1739);
DISPLAY 0.638298 (2089 1739);
PAINT MONO (2089 1739);
FORCEPROP 2 LAST $XR3 201 
J 0
(2449 1775);
DISPLAY 0.638298 (2449 1775);
PAINT MONO (2449 1775);
FORCEPROP 2 LAST $XR2 194 
J 0
(2329 1775);
DISPLAY 0.638298 (2329 1775);
PAINT MONO (2329 1775);
FORCEPROP 2 LAST $XR1 193 
J 0
(2209 1775);
DISPLAY 0.638298 (2209 1775);
PAINT MONO (2209 1775);
FORCEPROP 2 LAST $XR0 138 
J 0
(2089 1775);
DISPLAY 0.638298 (2089 1775);
PAINT MONO (2089 1775);
FORCEADD OFFPAGE..2
(1875 1600);
FORCEPROP 2 LAST PATH I83
J 0
(2200 1650);
DISPLAY 1.021277 (2200 1650);
PAINT ORANGE (2200 1650);
DISPLAY INVISIBLE (2200 1650);
FORCEPROP 1 LAST OFFPAGE TRUE
J 0
(2200 1475);
DISPLAY 0.872340 (2200 1475);
PAINT GREEN (2200 1475);
DISPLAY INVISIBLE (2200 1475);
FORCEPROP 2 LAST CDS_LIB mstr_standard
J 0
(1875 1600);
PAINT ORANGE (1875 1600);
DISPLAY INVISIBLE (1875 1600);
FORCEPROP 1 LAST COMMENT_BODY TRUE
J 0
(1830 1505);
DISPLAY 0.872340 (1830 1505);
PAINT GREEN (1830 1505);
DISPLAY INVISIBLE (1830 1505);
FORCEPROP 2 LAST $XR11 226 
J 0
(2664 1564);
DISPLAY 0.638298 (2664 1564);
PAINT MONO (2664 1564);
FORCEPROP 2 LAST $XR10 223 
J 0
(2544 1564);
DISPLAY 0.638298 (2544 1564);
PAINT MONO (2544 1564);
FORCEPROP 2 LAST $XR9 218 
J 0
(2424 1564);
DISPLAY 0.638298 (2424 1564);
PAINT MONO (2424 1564);
FORCEPROP 2 LAST $XR8 215 
J 0
(2304 1564);
DISPLAY 0.638298 (2304 1564);
PAINT MONO (2304 1564);
FORCEPROP 2 LAST $XR7 206 
J 0
(2184 1564);
DISPLAY 0.638298 (2184 1564);
PAINT MONO (2184 1564);
FORCEPROP 2 LAST $XR6 201 
J 0
(2064 1564);
DISPLAY 0.638298 (2064 1564);
PAINT MONO (2064 1564);
FORCEPROP 2 LAST $XR5 194 
J 0
(2664 1600);
DISPLAY 0.638298 (2664 1600);
PAINT MONO (2664 1600);
FORCEPROP 2 LAST $XR4 193 
J 0
(2544 1600);
DISPLAY 0.638298 (2544 1600);
PAINT MONO (2544 1600);
FORCEPROP 2 LAST $XR3 235 
J 0
(2424 1600);
DISPLAY 0.638298 (2424 1600);
PAINT MONO (2424 1600);
FORCEPROP 2 LAST $XR2 213 
J 0
(2304 1600);
DISPLAY 0.638298 (2304 1600);
PAINT MONO (2304 1600);
FORCEPROP 2 LAST $XR1 211 
J 0
(2184 1600);
DISPLAY 0.638298 (2184 1600);
PAINT MONO (2184 1600);
FORCEPROP 2 LAST $XR0 138 
J 0
(2064 1600);
DISPLAY 0.638298 (2064 1600);
PAINT MONO (2064 1600);
FORCEADD INTEL_CORP_BPAGE..1
(2650 500);
FORCEPROP 1 LAST CDS_CON_LAST_MODIFIED Tue Dec 01 15:51:25 2015
J 0
(1225 825);
PAINT ORANGE (1225 825);
DISPLAY INVISIBLE (1225 825);
FORCEPROP 1 LAST CUSTOM_TXT_CDS <CURRENT_DESIGN_SHEET> OF <TOTAL_DESIGN_SHEETS>
J 0
(2150 525);
PAINT ORANGE (2150 525);
FORCEPROP 1 LAST CUSTOM_TXT_CDS <CON_LAST_MODIFIED>
J 0
(725 850);
PAINT ORANGE (725 850);
FORCEPROP 2 LAST CUSTOM_TXT_CDS <XR_PAGE_TITLE>
J 0
(-5240 5750);
DISPLAY 0.638298 (-5240 5750);
PAINT PINK (-5240 5750);
DISPLAY INVISIBLE (-5240 5750);
FORCEPROP 2 LAST CDS_XR_PAGE_TITLE CR-159 : @BASEBOARD_FAB2_LIB.BASEBOARD_FAB2(SCH_1):PAGE159
J 0
(-5240 5750);
DISPLAY 0.638298 (-5240 5750);
PAINT PINK (-5240 5750);
DISPLAY INVISIBLE (-5240 5750);
FORCEPROP 1 LAST COMMENT_BODY TRUE
J 0
(2662 512);
DISPLAY 0.468085 (2662 512);
PAINT GREEN (2662 512);
DISPLAY INVISIBLE (2662 512);
FORCEPROP 2 LAST CDS_LIB mstr_symbols
J 0
(2650 500);
PAINT MONO (2650 500);
DISPLAY INVISIBLE (2650 500);
FORCEPROP 2 LAST PAGE_BORDER TRUE
J 0
(-5240 5750);
DISPLAY 0.851064 (-5240 5750);
PAINT PINK (-5240 5750);
DISPLAY INVISIBLE (-5240 5750);
FORCEPROP 1 LAST SCH_NUMBER H4694802
J 0
(1350 650);
DISPLAY 1.212766 (1350 650);
PAINT YELLOW (1350 650);
FORCEPROP 1 LAST SCH_DEPT BESD
J 1
(-1800 600);
DISPLAY 1.212766 (-1800 600);
PAINT YELLOW (-1800 600);
FORCEPROP 1 LAST SCH_REV 2.420
J 0
(2400 650);
DISPLAY 0.978723 (2400 650);
PAINT YELLOW (2400 650);
FORCEPROP 1 LAST SCH_ADDRESS1 2200 Mission College Blvd.
J 0
(-1325 625);
DISPLAY 0.617021 (-1325 625);
PAINT GREEN (-1325 625);
FORCEPROP 1 LAST SCH_ADDRESS2 P.O. BOX 58119
J 0
(-1325 575);
DISPLAY 0.617021 (-1325 575);
PAINT GREEN (-1325 575);
FORCEPROP 1 LAST SCH_ADDRESS3 Santa Clara, CA 95052-8119
J 0
(-1325 525);
DISPLAY 0.617021 (-1325 525);
PAINT GREEN (-1325 525);
FORCEPROP 1 LAST SCH_TITLE SMBUS PULLUPS (1 OF 2)
J 0
(-5300 550);
DISPLAY 1.212766 (-5300 550);
PAINT ORANGE (-5300 550);
FORCEADD DNS..2
(-3720 2895);
PAINT RED (-3720 2895);
FORCEPROP 2 LAST CDS_LIB mstr_misc
J 0
(-3720 2895);
PAINT ORANGE (-3720 2895);
DISPLAY INVISIBLE (-3720 2895);
FORCEPROP 1 LAST COMMENT_BODY TRUE
R 1
J 0
(-3645 2670);
DISPLAY 0.872340 (-3645 2670);
PAINT GREEN (-3645 2670);
DISPLAY INVISIBLE (-3645 2670);
FORCEADD DNS..2
(-3370 2895);
PAINT RED (-3370 2895);
FORCEPROP 2 LAST CDS_LIB mstr_misc
J 0
(-3370 2895);
PAINT ORANGE (-3370 2895);
DISPLAY INVISIBLE (-3370 2895);
FORCEPROP 1 LAST COMMENT_BODY TRUE
R 1
J 0
(-3295 2670);
DISPLAY 0.872340 (-3295 2670);
PAINT GREEN (-3295 2670);
DISPLAY INVISIBLE (-3295 2670);
FORCEADD CAD_NOTE..1
(600 1475);
FORCEPROP 1 LAST COMMENT_BODY TRUE
J 0
(625 1575);
DISPLAY 0.978723 (625 1575);
PAINT ORANGE (625 1575);
DISPLAY INVISIBLE (625 1575);
FORCEPROP 2 LAST CDS_LIB mstr_symbols
J 0
(600 1475);
PAINT ORANGE (600 1475);
DISPLAY INVISIBLE (600 1475);
FORCEPROP 0 LAST L1 PLACE RESISTORS CLOSE TO BMC
J 0
(-75 1325);
DISPLAY 1.021277 (-75 1325);
PAINT ORANGE (-75 1325);
FORCEADD CAD_NOTE..1
(-3300 2175);
FORCEPROP 1 LAST COMMENT_BODY TRUE
J 0
(-3275 2275);
DISPLAY 0.978723 (-3275 2275);
PAINT ORANGE (-3275 2275);
DISPLAY INVISIBLE (-3275 2275);
FORCEPROP 2 LAST CDS_LIB mstr_symbols
J 0
(-3300 2175);
PAINT ORANGE (-3300 2175);
DISPLAY INVISIBLE (-3300 2175);
FORCEPROP 0 LAST L1 PLACE RESISTORS CLOSE TO BMC
J 0
(-3975 2025);
DISPLAY 1.021277 (-3975 2025);
PAINT ORANGE (-3975 2025);
FORCEADD CAD_NOTE..1
(-3875 1000);
FORCEPROP 1 LAST COMMENT_BODY TRUE
J 0
(-3850 1100);
DISPLAY 0.978723 (-3850 1100);
PAINT ORANGE (-3850 1100);
DISPLAY INVISIBLE (-3850 1100);
FORCEPROP 2 LAST CDS_LIB mstr_symbols
J 0
(-3875 1000);
PAINT MONO (-3875 1000);
DISPLAY INVISIBLE (-3875 1000);
FORCEPROP 0 LAST L1 RUN TRACES THROUGH RESISTOR PADS ON OCP AND SMLINK0 CONNECTIONS
J 0
(-4000 875);
DISPLAY 0.808511 (-4000 875);
PAINT ORANGE (-4000 875);
FORCEPROP 0 LAST L2 FOR QUESTIONS, ASK MAX
J 0
(-4000 825);
DISPLAY 0.808511 (-4000 825);
PAINT ORANGE (-4000 825);
WIRE 16 -1 (-3375 3150)(-3375 3000);
WIRE 16 -1 (-3725 3150)(-3725 3000);
WIRE 16 -1 (550 5075)(550 4925);
WIRE 16 -1 (200 5075)(200 4925);
WIRE 16 -1 (-3075 3775)(-2050 3775);
FORCEPROP 0 LAST SIG_NAME SMB_HOST_STBY_LVC3_SDA
J 2
(-2025 3785);
DISPLAY 0.617021 (-2025 3785);
PAINT ORANGE (-2025 3785);
WIRE 16 -1 (1125 4450)(1825 4450);
FORCEPROP 0 LAST SIG_NAME SMB_OCP_FRU_STBY_LVC3_SDA
J 2
(1850 4460);
DISPLAY 0.617021 (1850 4460);
PAINT ORANGE (1850 4460);
WIRE 16 -1 (1125 4275)(1825 4275);
FORCEPROP 0 LAST SIG_NAME SMB_OCP_FRU_STBY_LVC3_SCL
J 2
(1850 4285);
DISPLAY 0.617021 (1850 4285);
PAINT ORANGE (1850 4285);
WIRE 16 -1 (550 4275)(-600 4275);
FORCEPROP 2 LAST SIG_NAME SMB_OCP_FRU_STBY_LVC3_SCL_R
J 0
(-585 4285);
DISPLAY 0.617021 (-585 4285);
PAINT ORANGE (-585 4285);
WIRE 16 -1 (925 4275)(550 4275);
WIRE 16 -1 (550 4725)(550 4275);
WIRE 16 -1 (200 4450)(-600 4450);
FORCEPROP 2 LAST SIG_NAME SMB_OCP_FRU_STBY_LVC3_SDA_R
J 0
(-610 4460);
DISPLAY 0.617021 (-610 4460);
PAINT ORANGE (-610 4460);
WIRE 16 -1 (200 4725)(200 4450);
WIRE 16 -1 (925 4450)(200 4450);
WIRE 16 2175 (1175 5250)(-225 5250);
WIRE 16 2175 (1175 1250)(1175 5250);
WIRE 16 2175 (-225 5250)(-225 1250);
WIRE 16 2175 (-225 1250)(1175 1250);
WIRE 16 -1 (800 3550)(1825 3550);
FORCEPROP 0 LAST SIG_NAME SMB_BMC_PMBUS_STBY_LVC3_SDA
J 2
(1850 3560);
DISPLAY 0.617021 (1850 3560);
PAINT ORANGE (1850 3560);
WIRE 16 -1 (800 3375)(1825 3375);
FORCEPROP 0 LAST SIG_NAME SMB_BMC_PMBUS_STBY_LVC3_SCL
J 2
(1850 3385);
DISPLAY 0.617021 (1850 3385);
PAINT ORANGE (1850 3385);
WIRE 16 -1 (800 1600)(1825 1600);
FORCEPROP 0 LAST SIG_NAME SMB_VR_STBY_LVC3_SCL
J 2
(1850 1610);
DISPLAY 0.617021 (1850 1610);
PAINT ORANGE (1850 1610);
WIRE 16 -1 (800 1775)(1825 1775);
FORCEPROP 0 LAST SIG_NAME SMB_VR_STBY_LVC3_SDA
J 2
(1850 1785);
DISPLAY 0.617021 (1850 1785);
PAINT ORANGE (1850 1785);
WIRE 16 -1 (600 1600)(-550 1600);
FORCEPROP 2 LAST SIG_NAME SMB_VR_STBY_LVC3_SCL_R
J 0
(-535 1610);
DISPLAY 0.617021 (-535 1610);
PAINT ORANGE (-535 1610);
WIRE 16 -1 (600 1775)(-525 1775);
FORCEPROP 2 LAST SIG_NAME SMB_VR_STBY_LVC3_SDA_R
J 0
(-535 1785);
DISPLAY 0.617021 (-535 1785);
PAINT ORANGE (-535 1785);
WIRE 16 -1 (600 3550)(-550 3550);
FORCEPROP 2 LAST SIG_NAME SMB_BMC_PMBUS_STBY_LVC3_SDA_R
J 0
(-560 3560);
DISPLAY 0.617021 (-560 3560);
PAINT ORANGE (-560 3560);
WIRE 16 -1 (600 3375)(-575 3375);
FORCEPROP 2 LAST SIG_NAME SMB_BMC_PMBUS_STBY_LVC3_SCL_R
J 0
(-560 3385);
DISPLAY 0.617021 (-560 3385);
PAINT ORANGE (-560 3385);
WIRE 16 -1 (-3075 4200)(-2050 4200);
FORCEPROP 0 LAST SIG_NAME SMB_SMLINK0_STBY_LVC3_SCL
J 2
(-2025 4210);
DISPLAY 0.617021 (-2025 4210);
PAINT ORANGE (-2025 4210);
WIRE 16 -1 (-3075 4375)(-2050 4375);
FORCEPROP 0 LAST SIG_NAME SMB_SMLINK0_STBY_LVC3_SDA
J 2
(-2025 4385);
DISPLAY 0.617021 (-2025 4385);
PAINT ORANGE (-2025 4385);
WIRE 16 2175 (-4025 4575)(-4025 1925);
WIRE 16 2175 (-2675 4575)(-4025 4575);
WIRE 16 2175 (-4025 1925)(-2675 1925);
WIRE 16 2175 (-2675 1925)(-2675 4575);
WIRE 16 -1 (-2000 2350)(-2775 2350);
FORCEPROP 0 LAST SIG_NAME SMB_OCP_LAN_STBY_LVC3_SCL
J 2
(-1975 2360);
DISPLAY 0.617021 (-1975 2360);
PAINT ORANGE (-1975 2360);
WIRE 16 -1 (-2000 2525)(-2775 2525);
FORCEPROP 0 LAST SIG_NAME SMB_OCP_LAN_STBY_LVC3_SDA
J 2
(-1975 2535);
DISPLAY 0.617021 (-1975 2535);
PAINT ORANGE (-1975 2535);
WIRE 16 -1 (-3075 3600)(-2050 3600);
FORCEPROP 0 LAST SIG_NAME SMB_HOST_STBY_LVC3_SCL
J 2
(-2025 3610);
DISPLAY 0.617021 (-2025 3610);
PAINT ORANGE (-2025 3610);
WIRE 16 -1 (-3375 2350)(-4350 2350);
FORCEPROP 2 LAST SIG_NAME SMB_OCP_LAN_STBY_LVC3_SCL_R
J 0
(-4335 2360);
DISPLAY 0.617021 (-4335 2360);
PAINT ORANGE (-4335 2360);
WIRE 16 -1 (-3375 2800)(-3375 2350);
WIRE 16 -1 (-2975 2350)(-3375 2350);
WIRE 16 -1 (-3725 2525)(-4350 2525);
FORCEPROP 2 LAST SIG_NAME SMB_OCP_LAN_STBY_LVC3_SDA_R
J 0
(-4360 2535);
DISPLAY 0.617021 (-4360 2535);
PAINT ORANGE (-4360 2535);
WIRE 16 -1 (-3725 2800)(-3725 2525);
WIRE 16 -1 (-2975 2525)(-3725 2525);
WIRE 16 3135 (-3175 1075)(-2300 1075);
WIRE 16 3135 (-2300 750)(-2300 1075);
WIRE 16 3135 (-3175 1075)(-3175 1675);
WIRE 16 3135 (-3175 1675)(-3950 1675);
WIRE 16 3135 (-4100 750)(-2300 750);
WIRE 16 3135 (-4100 1125)(-4100 750);
WIRE 16 3135 (-3950 1675)(-3950 1125);
WIRE 16 3135 (-3950 1125)(-4100 1125);
WIRE 16 -1 (-3100 1575)(-3525 1575);
WIRE 16 -1 (-3525 1450)(-3100 1450);
WIRE 16 -1 (-3100 1450)(-3100 1575);
WIRE 16 -1 (-3100 1450)(-2550 1450);
FORCEPROP 2 LAST SIG_NAME SMB_SPRINGVILLE_STBY_LVC3_SDA
J 0
(-3085 1460);
DISPLAY 0.617021 (-3085 1460);
PAINT ORANGE (-3085 1460);
WIRE 16 -1 (-3100 1200)(-3525 1200);
WIRE 16 -1 (-3525 1325)(-3100 1325);
WIRE 16 -1 (-3100 1325)(-2550 1325);
FORCEPROP 2 LAST SIG_NAME SMB_SPRINGVILLE_STBY_LVC3_SCL
J 0
(-3085 1335);
DISPLAY 0.617021 (-3085 1335);
PAINT ORANGE (-3085 1335);
WIRE 16 -1 (-3100 1325)(-3100 1200);
WIRE 16 -1 (-4575 1200)(-3725 1200);
FORCEPROP 2 LAST SIG_NAME SMB_OCP_LAN_STBY_LVC3_SCL
J 0
(-4535 1210);
DISPLAY 0.617021 (-4535 1210);
PAINT ORANGE (-4535 1210);
WIRE 16 -1 (-4575 1575)(-3725 1575);
FORCEPROP 2 LAST SIG_NAME SMB_OCP_LAN_STBY_LVC3_SDA
J 0
(-4535 1585);
DISPLAY 0.617021 (-4535 1585);
PAINT ORANGE (-4535 1585);
WIRE 16 -1 (-4575 1325)(-3725 1325);
FORCEPROP 2 LAST SIG_NAME SMB_SMLINK0_STBY_LVC3_SCL
J 0
(-4535 1335);
DISPLAY 0.617021 (-4535 1335);
PAINT ORANGE (-4535 1335);
WIRE 16 -1 (-4575 1450)(-3725 1450);
FORCEPROP 2 LAST SIG_NAME SMB_SMLINK0_STBY_LVC3_SDA
J 0
(-4535 1460);
DISPLAY 0.617021 (-4535 1460);
PAINT ORANGE (-4535 1460);
WIRE 16 -1 (-3275 3600)(-4400 3600);
FORCEPROP 2 LAST SIG_NAME SMB_HOST_STBY_LVC3_SCL_R
J 0
(-4385 3610);
DISPLAY 0.617021 (-4385 3610);
PAINT ORANGE (-4385 3610);
WIRE 16 -1 (-3275 3775)(-4400 3775);
FORCEPROP 2 LAST SIG_NAME SMB_HOST_STBY_LVC3_SDA_R
J 0
(-4410 3785);
DISPLAY 0.617021 (-4410 3785);
PAINT ORANGE (-4410 3785);
WIRE 16 -1 (-3275 4200)(-4400 4200);
FORCEPROP 2 LAST SIG_NAME SMB_SMLINK0_STBY_LVC3_SCL_R
J 0
(-4385 4210);
DISPLAY 0.617021 (-4385 4210);
PAINT ORANGE (-4385 4210);
WIRE 16 -1 (-3275 4375)(-4400 4375);
FORCEPROP 2 LAST SIG_NAME SMB_SMLINK0_STBY_LVC3_SDA_R
J 0
(-4410 4385);
DISPLAY 0.617021 (-4410 4385);
PAINT ORANGE (-4410 4385);
DOT 1 (-3100 1450);
DOT 1 (-3100 1325);
DOT 1 (-3725 2525);
DOT 1 (-3375 2350);
DOT 1 (200 4450);
DOT 1 (550 4275);
FORCENOTE
ROOM=SMBUS
(-5280 675) 0;
DISPLAY LEFT (-5280 675);
DISPLAY 0.617021 (-5280 675);
PAINT PURPLE (-5280 675);
QUIT
